FILE_TYPE = MACRO_DRAWING;
SET COLOR_WIRE YELLOW;
SET COLOR_PROP MONO;
SET COLOR_DOT WHITE;
SET COLOR_ARC YELLOW;
SET COLOR_BODY GREEN;
SET COLOR_NOTE MONO;
SET PROP_DISPLAY VALUE;
SET PAGE_NUMBER P40;
FORCEADD GND..1
(-2625 450);
FORCEPROP 3 LASTPIN (-2625 500) SIG_NAME GND\g
J 0
(-2615 510);
DISPLAY 0.659574 (-2615 510);
PAINT MONO (-2615 510);
DISPLAY INVISIBLE (-2615 510);
FORCEPROP 1 LAST VOLTAGE 0.0V
J 0
(-2670 407);
DISPLAY 0.340426 (-2670 407);
PAINT SKYBLUE (-2670 407);
DISPLAY INVISIBLE (-2670 407);
FORCEPROP 1 LAST SIZE 1B
J 0
(-2550 400);
DISPLAY 1.170213 (-2550 400);
PAINT AQUA (-2550 400);
DISPLAY INVISIBLE (-2550 400);
FORCEPROP 2 LAST CDS_LIB mstr_symbols
J 0
(-2625 450);
PAINT ORANGE (-2625 450);
DISPLAY INVISIBLE (-2625 450);
FORCEPROP 1 LAST BODY_TYPE PLUMBING
J 0
(-2670 407);
DISPLAY 0.340426 (-2670 407);
PAINT GREEN (-2670 407);
DISPLAY INVISIBLE (-2670 407);
FORCEPROP 1 LAST PATH I11
J 0
(-2550 450);
DISPLAY 0.872340 (-2550 450);
PAINT AQUA (-2550 450);
DISPLAY INVISIBLE (-2550 450);
FORCEPROP 1 LAST HDL_POWER GND
J 0
(-2625 600);
DISPLAY 1.170213 (-2625 600);
PAINT GREEN (-2625 600);
DISPLAY INVISIBLE (-2625 600);
FORCEADD GND..1
(-775 450);
FORCEPROP 3 LASTPIN (-775 500) SIG_NAME GND\g
J 0
(-765 510);
DISPLAY 0.659574 (-765 510);
PAINT MONO (-765 510);
DISPLAY INVISIBLE (-765 510);
FORCEPROP 1 LAST VOLTAGE 0.0V
J 0
(-820 407);
DISPLAY 0.340426 (-820 407);
PAINT SKYBLUE (-820 407);
DISPLAY INVISIBLE (-820 407);
FORCEPROP 2 LAST CDS_LIB mstr_symbols
J 0
(-775 450);
PAINT ORANGE (-775 450);
DISPLAY INVISIBLE (-775 450);
FORCEPROP 1 LAST SIZE 1B
J 0
(-700 400);
DISPLAY 1.170213 (-700 400);
PAINT AQUA (-700 400);
DISPLAY INVISIBLE (-700 400);
FORCEPROP 1 LAST BODY_TYPE PLUMBING
J 0
(-820 407);
DISPLAY 0.340426 (-820 407);
PAINT GREEN (-820 407);
DISPLAY INVISIBLE (-820 407);
FORCEPROP 1 LAST PATH I13
J 0
(-700 450);
DISPLAY 0.872340 (-700 450);
PAINT AQUA (-700 450);
DISPLAY INVISIBLE (-700 450);
FORCEPROP 1 LAST HDL_POWER GND
J 0
(-775 600);
DISPLAY 1.170213 (-775 600);
PAINT GREEN (-775 600);
DISPLAY INVISIBLE (-775 600);
FORCEADD GND..1
(-2325 475);
FORCEPROP 3 LASTPIN (-2325 525) SIG_NAME GND\g
J 0
(-2315 535);
DISPLAY 0.659574 (-2315 535);
PAINT MONO (-2315 535);
DISPLAY INVISIBLE (-2315 535);
FORCEPROP 1 LAST VOLTAGE 0.0V
J 0
(-2370 432);
DISPLAY 0.340426 (-2370 432);
PAINT SKYBLUE (-2370 432);
DISPLAY INVISIBLE (-2370 432);
FORCEPROP 2 LAST CDS_LIB mstr_symbols
J 0
(-2325 475);
PAINT ORANGE (-2325 475);
DISPLAY INVISIBLE (-2325 475);
FORCEPROP 1 LAST SIZE 1B
J 0
(-2250 425);
DISPLAY 1.170213 (-2250 425);
PAINT AQUA (-2250 425);
DISPLAY INVISIBLE (-2250 425);
FORCEPROP 1 LAST BODY_TYPE PLUMBING
J 0
(-2370 432);
DISPLAY 0.340426 (-2370 432);
PAINT GREEN (-2370 432);
DISPLAY INVISIBLE (-2370 432);
FORCEPROP 1 LAST PATH I14
J 0
(-2250 475);
DISPLAY 0.872340 (-2250 475);
PAINT AQUA (-2250 475);
DISPLAY INVISIBLE (-2250 475);
FORCEPROP 1 LAST HDL_POWER GND
J 0
(-2325 625);
DISPLAY 1.170213 (-2325 625);
PAINT GREEN (-2325 625);
DISPLAY INVISIBLE (-2325 625);
FORCEADD SKX_EXT_B..23
(-7050 2575);
FORCEPROP 2 LASTPIN (-6450 1625) $PN H33
J 0
(-6440 1635);
DISPLAY 0.617021 (-6440 1635);
PAINT ORANGE (-6440 1635);
FORCEPROP 1 LAST LOCATION U5D1
J 0
(-7600 4825);
DISPLAY 0.617021 (-7600 4825);
PAINT AQUA (-7600 4825);
FORCEPROP 1 LAST PART_NUMBER TBD
J 0
(-7600 425);
DISPLAY 0.617021 (-7600 425);
PAINT BLUE (-7600 425);
FORCEPROP 1 LAST MATERIAL IC
J 0
(-7600 4775);
DISPLAY 0.617021 (-7600 4775);
PAINT SKYBLUE (-7600 4775);
FORCEPROP 2 LASTPIN (-7650 4525) $PN A42
J 2
(-7660 4535);
DISPLAY 0.617021 (-7660 4535);
PAINT ORANGE (-7660 4535);
FORCEPROP 2 LASTPIN (-7650 4475) $PN B43
J 2
(-7660 4485);
DISPLAY 0.617021 (-7660 4485);
PAINT ORANGE (-7660 4485);
FORCEPROP 2 LASTPIN (-7650 4425) $PN B5
J 2
(-7660 4435);
DISPLAY 0.617021 (-7660 4435);
PAINT ORANGE (-7660 4435);
FORCEPROP 2 LASTPIN (-7650 4375) $PN B79
J 2
(-7660 4385);
DISPLAY 0.617021 (-7660 4385);
PAINT ORANGE (-7660 4385);
FORCEPROP 2 LASTPIN (-7650 4325) $PN C4
J 2
(-7660 4335);
DISPLAY 0.617021 (-7660 4335);
PAINT ORANGE (-7660 4335);
FORCEPROP 2 LASTPIN (-7650 4275) $PN C80
J 2
(-7660 4285);
DISPLAY 0.617021 (-7660 4285);
PAINT ORANGE (-7660 4285);
FORCEPROP 2 LASTPIN (-7650 4225) $PN D3
J 2
(-7660 4235);
DISPLAY 0.617021 (-7660 4235);
PAINT ORANGE (-7660 4235);
FORCEPROP 2 LASTPIN (-7650 4175) $PN D81
J 2
(-7660 4185);
DISPLAY 0.617021 (-7660 4185);
PAINT ORANGE (-7660 4185);
FORCEPROP 2 LASTPIN (-7650 4125) $PN E82
J 2
(-7660 4135);
DISPLAY 0.617021 (-7660 4135);
PAINT ORANGE (-7660 4135);
FORCEPROP 2 LASTPIN (-7650 4075) $PN J86
J 2
(-7660 4085);
DISPLAY 0.617021 (-7660 4085);
PAINT ORANGE (-7660 4085);
FORCEPROP 2 LASTPIN (-7650 4025) $PN DY85
J 2
(-7660 4035);
DISPLAY 0.617021 (-7660 4035);
PAINT ORANGE (-7660 4035);
FORCEPROP 2 LASTPIN (-7650 3975) $PN EA84
J 2
(-7660 3985);
DISPLAY 0.617021 (-7660 3985);
PAINT ORANGE (-7660 3985);
FORCEPROP 2 LASTPIN (-7650 3925) $PN EB83
J 2
(-7660 3935);
DISPLAY 0.617021 (-7660 3935);
PAINT ORANGE (-7660 3935);
FORCEPROP 2 LASTPIN (-7650 3875) $PN DW2
J 2
(-7660 3885);
DISPLAY 0.617021 (-7660 3885);
PAINT ORANGE (-7660 3885);
FORCEPROP 2 LASTPIN (-7650 3825) $PN EC42
J 2
(-7660 3835);
DISPLAY 0.617021 (-7660 3835);
PAINT ORANGE (-7660 3835);
FORCEPROP 2 LASTPIN (-7650 3775) $PN EC6
J 2
(-7660 3785);
DISPLAY 0.617021 (-7660 3785);
PAINT ORANGE (-7660 3785);
FORCEPROP 2 LASTPIN (-7650 3725) $PN EC82
J 2
(-7660 3735);
DISPLAY 0.617021 (-7660 3735);
PAINT ORANGE (-7660 3735);
FORCEPROP 2 LASTPIN (-7650 3675) $PN ED41
J 2
(-7660 3685);
DISPLAY 0.617021 (-7660 3685);
PAINT ORANGE (-7660 3685);
FORCEPROP 2 LASTPIN (-7650 3625) $PN ED7
J 2
(-7660 3635);
DISPLAY 0.617021 (-7660 3635);
PAINT ORANGE (-7660 3635);
FORCEPROP 2 LASTPIN (-7650 3575) $PN ED81
J 2
(-7660 3585);
DISPLAY 0.617021 (-7660 3585);
PAINT ORANGE (-7660 3585);
FORCEPROP 2 LASTPIN (-7650 3525) $PN EE40
J 2
(-7660 3535);
DISPLAY 0.617021 (-7660 3535);
PAINT ORANGE (-7660 3535);
FORCEPROP 2 LASTPIN (-7650 3475) $PN EE8
J 2
(-7660 3485);
DISPLAY 0.617021 (-7660 3485);
PAINT ORANGE (-7660 3485);
FORCEPROP 2 LASTPIN (-7650 3425) $PN EE80
J 2
(-7660 3435);
DISPLAY 0.617021 (-7660 3435);
PAINT ORANGE (-7660 3435);
FORCEPROP 2 LASTPIN (-7650 3375) $PN ED69
J 2
(-7660 3385);
DISPLAY 0.617021 (-7660 3385);
PAINT ORANGE (-7660 3385);
FORCEPROP 2 LASTPIN (-7650 3325) $PN E66
J 2
(-7660 3335);
DISPLAY 0.617021 (-7660 3335);
PAINT ORANGE (-7660 3335);
FORCEPROP 2 LASTPIN (-7650 3275) $PN V11
J 2
(-7660 3285);
DISPLAY 0.617021 (-7660 3285);
PAINT ORANGE (-7660 3285);
FORCEPROP 2 LASTPIN (-7650 3225) $PN L8
J 2
(-7660 3235);
DISPLAY 0.617021 (-7660 3235);
PAINT ORANGE (-7660 3235);
FORCEPROP 2 LASTPIN (-7650 3175) $PN EA14
J 2
(-7660 3185);
DISPLAY 0.617021 (-7660 3185);
PAINT ORANGE (-7660 3185);
FORCEPROP 2 LASTPIN (-7650 3125) $PN DY63
J 2
(-7660 3135);
DISPLAY 0.617021 (-7660 3135);
PAINT ORANGE (-7660 3135);
FORCEPROP 2 LASTPIN (-7650 3075) $PN DY61
J 2
(-7660 3085);
DISPLAY 0.617021 (-7660 3085);
PAINT ORANGE (-7660 3085);
FORCEPROP 2 LASTPIN (-7650 3025) $PN DY59
J 2
(-7660 3035);
DISPLAY 0.617021 (-7660 3035);
PAINT ORANGE (-7660 3035);
FORCEPROP 2 LASTPIN (-7650 2975) $PN DY57
J 2
(-7660 2985);
DISPLAY 0.617021 (-7660 2985);
PAINT ORANGE (-7660 2985);
FORCEPROP 2 LASTPIN (-7650 2925) $PN DY55
J 2
(-7660 2935);
DISPLAY 0.617021 (-7660 2935);
PAINT ORANGE (-7660 2935);
FORCEPROP 2 LASTPIN (-7650 2875) $PN DY53
J 2
(-7660 2885);
DISPLAY 0.617021 (-7660 2885);
PAINT ORANGE (-7660 2885);
FORCEPROP 2 LASTPIN (-7650 2825) $PN DY51
J 2
(-7660 2835);
DISPLAY 0.617021 (-7660 2835);
PAINT ORANGE (-7660 2835);
FORCEPROP 2 LASTPIN (-7650 2775) $PN DY49
J 2
(-7660 2785);
DISPLAY 0.617021 (-7660 2785);
PAINT ORANGE (-7660 2785);
FORCEPROP 2 LASTPIN (-7650 2725) $PN DY47
J 2
(-7660 2735);
DISPLAY 0.617021 (-7660 2735);
PAINT ORANGE (-7660 2735);
FORCEPROP 2 LASTPIN (-7650 2675) $PN DY45
J 2
(-7660 2685);
DISPLAY 0.617021 (-7660 2685);
PAINT ORANGE (-7660 2685);
FORCEPROP 2 LASTPIN (-7650 2625) $PN DV19
J 2
(-7660 2635);
DISPLAY 0.617021 (-7660 2635);
PAINT ORANGE (-7660 2635);
FORCEPROP 2 LASTPIN (-7650 2575) $PN DP9
J 2
(-7660 2585);
DISPLAY 0.617021 (-7660 2585);
PAINT ORANGE (-7660 2585);
FORCEPROP 2 LASTPIN (-7650 2525) $PN DP63
J 2
(-7660 2535);
DISPLAY 0.617021 (-7660 2535);
PAINT ORANGE (-7660 2535);
FORCEPROP 2 LASTPIN (-7650 2475) $PN DP61
J 2
(-7660 2485);
DISPLAY 0.617021 (-7660 2485);
PAINT ORANGE (-7660 2485);
FORCEPROP 2 LASTPIN (-7650 2425) $PN DP59
J 2
(-7660 2435);
DISPLAY 0.617021 (-7660 2435);
PAINT ORANGE (-7660 2435);
FORCEPROP 2 LASTPIN (-7650 2375) $PN DP57
J 2
(-7660 2385);
DISPLAY 0.617021 (-7660 2385);
PAINT ORANGE (-7660 2385);
FORCEPROP 2 LASTPIN (-7650 2325) $PN DP55
J 2
(-7660 2335);
DISPLAY 0.617021 (-7660 2335);
PAINT ORANGE (-7660 2335);
FORCEPROP 2 LASTPIN (-7650 2275) $PN DP53
J 2
(-7660 2285);
DISPLAY 0.617021 (-7660 2285);
PAINT ORANGE (-7660 2285);
FORCEPROP 2 LASTPIN (-7650 2225) $PN DP51
J 2
(-7660 2235);
DISPLAY 0.617021 (-7660 2235);
PAINT ORANGE (-7660 2235);
FORCEPROP 2 LASTPIN (-7650 2175) $PN DP49
J 2
(-7660 2185);
DISPLAY 0.617021 (-7660 2185);
PAINT ORANGE (-7660 2185);
FORCEPROP 2 LASTPIN (-7650 2125) $PN DP47
J 2
(-7660 2135);
DISPLAY 0.617021 (-7660 2135);
PAINT ORANGE (-7660 2135);
FORCEPROP 2 LASTPIN (-7650 2075) $PN DP45
J 2
(-7660 2085);
DISPLAY 0.617021 (-7660 2085);
PAINT ORANGE (-7660 2085);
FORCEPROP 2 LASTPIN (-7650 2025) $PN DN18
J 2
(-7660 2035);
DISPLAY 0.617021 (-7660 2035);
PAINT ORANGE (-7660 2035);
FORCEPROP 2 LASTPIN (-7650 1975) $PN DL8
J 2
(-7660 1985);
DISPLAY 0.617021 (-7660 1985);
PAINT ORANGE (-7660 1985);
FORCEPROP 2 LASTPIN (-7650 1925) $PN DE62
J 2
(-7660 1935);
DISPLAY 0.617021 (-7660 1935);
PAINT ORANGE (-7660 1935);
FORCEPROP 2 LASTPIN (-7650 1875) $PN DE60
J 2
(-7660 1885);
DISPLAY 0.617021 (-7660 1885);
PAINT ORANGE (-7660 1885);
FORCEPROP 2 LASTPIN (-7650 1825) $PN DE58
J 2
(-7660 1835);
DISPLAY 0.617021 (-7660 1835);
PAINT ORANGE (-7660 1835);
FORCEPROP 2 LASTPIN (-7650 1775) $PN DE56
J 2
(-7660 1785);
DISPLAY 0.617021 (-7660 1785);
PAINT ORANGE (-7660 1785);
FORCEPROP 2 LASTPIN (-7650 1725) $PN DE54
J 2
(-7660 1735);
DISPLAY 0.617021 (-7660 1735);
PAINT ORANGE (-7660 1735);
FORCEPROP 2 LASTPIN (-7650 1675) $PN DE52
J 2
(-7660 1685);
DISPLAY 0.617021 (-7660 1685);
PAINT ORANGE (-7660 1685);
FORCEPROP 2 LASTPIN (-7650 1625) $PN DE50
J 2
(-7660 1635);
DISPLAY 0.617021 (-7660 1635);
PAINT ORANGE (-7660 1635);
FORCEPROP 2 LASTPIN (-7650 1575) $PN DE48
J 2
(-7660 1585);
DISPLAY 0.617021 (-7660 1585);
PAINT ORANGE (-7660 1585);
FORCEPROP 2 LASTPIN (-7650 1525) $PN CW6
J 2
(-7660 1535);
DISPLAY 0.617021 (-7660 1535);
PAINT ORANGE (-7660 1535);
FORCEPROP 2 LASTPIN (-7650 1475) $PN CG6
J 2
(-7660 1485);
DISPLAY 0.617021 (-7660 1485);
PAINT ORANGE (-7660 1485);
FORCEPROP 2 LASTPIN (-7650 1425) $PN AR6
J 2
(-7660 1435);
DISPLAY 0.617021 (-7660 1435);
PAINT ORANGE (-7660 1435);
FORCEPROP 2 LASTPIN (-7650 1375) $PN AJ4
J 2
(-7660 1385);
DISPLAY 0.617021 (-7660 1385);
PAINT ORANGE (-7660 1385);
FORCEPROP 2 LASTPIN (-7650 1325) $PN AC62
J 2
(-7660 1335);
DISPLAY 0.617021 (-7660 1335);
PAINT ORANGE (-7660 1335);
FORCEPROP 2 LASTPIN (-7650 1275) $PN AC60
J 2
(-7660 1285);
DISPLAY 0.617021 (-7660 1285);
PAINT ORANGE (-7660 1285);
FORCEPROP 2 LASTPIN (-7650 1225) $PN AC58
J 2
(-7660 1235);
DISPLAY 0.617021 (-7660 1235);
PAINT ORANGE (-7660 1235);
FORCEPROP 2 LASTPIN (-7650 1175) $PN A26
J 2
(-7660 1185);
DISPLAY 0.617021 (-7660 1185);
PAINT ORANGE (-7660 1185);
FORCEPROP 2 LASTPIN (-7650 1125) $PN A30
J 2
(-7660 1135);
DISPLAY 0.617021 (-7660 1135);
PAINT ORANGE (-7660 1135);
FORCEPROP 2 LASTPIN (-7650 1075) $PN A32
J 2
(-7660 1085);
DISPLAY 0.617021 (-7660 1085);
PAINT ORANGE (-7660 1085);
FORCEPROP 2 LASTPIN (-7650 1025) $PN A36
J 2
(-7660 1035);
DISPLAY 0.617021 (-7660 1035);
PAINT ORANGE (-7660 1035);
FORCEPROP 2 LASTPIN (-7650 975) $PN A38
J 2
(-7660 985);
DISPLAY 0.617021 (-7660 985);
PAINT ORANGE (-7660 985);
FORCEPROP 2 LASTPIN (-7650 925) $PN B25
J 2
(-7660 935);
DISPLAY 0.617021 (-7660 935);
PAINT ORANGE (-7660 935);
FORCEPROP 2 LASTPIN (-7650 875) $PN B31
J 2
(-7660 885);
DISPLAY 0.617021 (-7660 885);
PAINT ORANGE (-7660 885);
FORCEPROP 2 LASTPIN (-7650 825) $PN B37
J 2
(-7660 835);
DISPLAY 0.617021 (-7660 835);
PAINT ORANGE (-7660 835);
FORCEPROP 2 LASTPIN (-7650 775) $PN B71
J 2
(-7660 785);
DISPLAY 0.617021 (-7660 785);
PAINT ORANGE (-7660 785);
FORCEPROP 2 LASTPIN (-7650 725) $PN B75
J 2
(-7660 735);
DISPLAY 0.617021 (-7660 735);
PAINT ORANGE (-7660 735);
FORCEPROP 2 LASTPIN (-7650 675) $PN C8
J 2
(-7660 685);
DISPLAY 0.617021 (-7660 685);
PAINT ORANGE (-7660 685);
FORCEPROP 2 LASTPIN (-7650 625) $PN C10
J 2
(-7660 635);
DISPLAY 0.617021 (-7660 635);
PAINT ORANGE (-7660 635);
FORCEPROP 2 LASTPIN (-6450 4575) $PN C12
J 0
(-6440 4585);
DISPLAY 0.617021 (-6440 4585);
PAINT ORANGE (-6440 4585);
FORCEPROP 2 LASTPIN (-6450 4525) $PN C14
J 0
(-6440 4535);
DISPLAY 0.617021 (-6440 4535);
PAINT ORANGE (-6440 4535);
FORCEPROP 2 LASTPIN (-6450 4475) $PN C16
J 0
(-6440 4485);
DISPLAY 0.617021 (-6440 4485);
PAINT ORANGE (-6440 4485);
FORCEPROP 2 LASTPIN (-6450 4425) $PN C76
J 0
(-6440 4435);
DISPLAY 0.617021 (-6440 4435);
PAINT ORANGE (-6440 4435);
FORCEPROP 2 LASTPIN (-6450 4375) $PN C78
J 0
(-6440 4385);
DISPLAY 0.617021 (-6440 4385);
PAINT ORANGE (-6440 4385);
FORCEPROP 2 LASTPIN (-6450 4325) $PN CM27
J 0
(-6440 4335);
DISPLAY 0.617021 (-6440 4335);
PAINT ORANGE (-6440 4335);
FORCEPROP 2 LASTPIN (-6450 4275) $PN D11
J 0
(-6440 4285);
DISPLAY 0.617021 (-6440 4285);
PAINT ORANGE (-6440 4285);
FORCEPROP 2 LASTPIN (-6450 4225) $PN D13
J 0
(-6440 4235);
DISPLAY 0.617021 (-6440 4235);
PAINT ORANGE (-6440 4235);
FORCEPROP 2 LASTPIN (-6450 4175) $PN D25
J 0
(-6440 4185);
DISPLAY 0.617021 (-6440 4185);
PAINT ORANGE (-6440 4185);
FORCEPROP 2 LASTPIN (-6450 4125) $PN D27
J 0
(-6440 4135);
DISPLAY 0.617021 (-6440 4135);
PAINT ORANGE (-6440 4135);
FORCEPROP 2 LASTPIN (-6450 4075) $PN D29
J 0
(-6440 4085);
DISPLAY 0.617021 (-6440 4085);
PAINT ORANGE (-6440 4085);
FORCEPROP 2 LASTPIN (-6450 4025) $PN D31
J 0
(-6440 4035);
DISPLAY 0.617021 (-6440 4035);
PAINT ORANGE (-6440 4035);
FORCEPROP 2 LASTPIN (-6450 3975) $PN D33
J 0
(-6440 3985);
DISPLAY 0.617021 (-6440 3985);
PAINT ORANGE (-6440 3985);
FORCEPROP 2 LASTPIN (-6450 3925) $PN D35
J 0
(-6440 3935);
DISPLAY 0.617021 (-6440 3935);
PAINT ORANGE (-6440 3935);
FORCEPROP 2 LASTPIN (-6450 3875) $PN D37
J 0
(-6440 3885);
DISPLAY 0.617021 (-6440 3885);
PAINT ORANGE (-6440 3885);
FORCEPROP 2 LASTPIN (-6450 3825) $PN D39
J 0
(-6440 3835);
DISPLAY 0.617021 (-6440 3835);
PAINT ORANGE (-6440 3835);
FORCEPROP 2 LASTPIN (-6450 3775) $PN D41
J 0
(-6440 3785);
DISPLAY 0.617021 (-6440 3785);
PAINT ORANGE (-6440 3785);
FORCEPROP 2 LASTPIN (-6450 3725) $PN D43
J 0
(-6440 3735);
DISPLAY 0.617021 (-6440 3735);
PAINT ORANGE (-6440 3735);
FORCEPROP 2 LASTPIN (-6450 3675) $PN D77
J 0
(-6440 3685);
DISPLAY 0.617021 (-6440 3685);
PAINT ORANGE (-6440 3685);
FORCEPROP 2 LASTPIN (-6450 3625) $PN E6
J 0
(-6440 3635);
DISPLAY 0.617021 (-6440 3635);
PAINT ORANGE (-6440 3635);
FORCEPROP 2 LASTPIN (-6450 3575) $PN E8
J 0
(-6440 3585);
DISPLAY 0.617021 (-6440 3585);
PAINT ORANGE (-6440 3585);
FORCEPROP 2 LASTPIN (-6450 3525) $PN E16
J 0
(-6440 3535);
DISPLAY 0.617021 (-6440 3535);
PAINT ORANGE (-6440 3535);
FORCEPROP 2 LASTPIN (-6450 3475) $PN E18
J 0
(-6440 3485);
DISPLAY 0.617021 (-6440 3485);
PAINT ORANGE (-6440 3485);
FORCEPROP 2 LASTPIN (-6450 3425) $PN E20
J 0
(-6440 3435);
DISPLAY 0.617021 (-6440 3435);
PAINT ORANGE (-6440 3435);
FORCEPROP 2 LASTPIN (-6450 3375) $PN E22
J 0
(-6440 3385);
DISPLAY 0.617021 (-6440 3385);
PAINT ORANGE (-6440 3385);
FORCEPROP 2 LASTPIN (-6450 3325) $PN E72
J 0
(-6440 3335);
DISPLAY 0.617021 (-6440 3335);
PAINT ORANGE (-6440 3335);
FORCEPROP 2 LASTPIN (-6450 3275) $PN E74
J 0
(-6440 3285);
DISPLAY 0.617021 (-6440 3285);
PAINT ORANGE (-6440 3285);
FORCEPROP 2 LASTPIN (-6450 3225) $PN E76
J 0
(-6440 3235);
DISPLAY 0.617021 (-6440 3235);
PAINT ORANGE (-6440 3235);
FORCEPROP 2 LASTPIN (-6450 3175) $PN F5
J 0
(-6440 3185);
DISPLAY 0.617021 (-6440 3185);
PAINT ORANGE (-6440 3185);
FORCEPROP 2 LASTPIN (-6450 3125) $PN F17
J 0
(-6440 3135);
DISPLAY 0.617021 (-6440 3135);
PAINT ORANGE (-6440 3135);
FORCEPROP 2 LASTPIN (-6450 3075) $PN F19
J 0
(-6440 3085);
DISPLAY 0.617021 (-6440 3085);
PAINT ORANGE (-6440 3085);
FORCEPROP 2 LASTPIN (-6450 3025) $PN F25
J 0
(-6440 3035);
DISPLAY 0.617021 (-6440 3035);
PAINT ORANGE (-6440 3035);
FORCEPROP 2 LASTPIN (-6450 2975) $PN F31
J 0
(-6440 2985);
DISPLAY 0.617021 (-6440 2985);
PAINT ORANGE (-6440 2985);
FORCEPROP 2 LASTPIN (-6450 2925) $PN F37
J 0
(-6440 2935);
DISPLAY 0.617021 (-6440 2935);
PAINT ORANGE (-6440 2935);
FORCEPROP 2 LASTPIN (-6450 2875) $PN F43
J 0
(-6440 2885);
DISPLAY 0.617021 (-6440 2885);
PAINT ORANGE (-6440 2885);
FORCEPROP 2 LASTPIN (-6450 2825) $PN F67
J 0
(-6440 2835);
DISPLAY 0.617021 (-6440 2835);
PAINT ORANGE (-6440 2835);
FORCEPROP 2 LASTPIN (-6450 2775) $PN F69
J 0
(-6440 2785);
DISPLAY 0.617021 (-6440 2785);
PAINT ORANGE (-6440 2785);
FORCEPROP 2 LASTPIN (-6450 2675) $PN G8
J 0
(-6440 2685);
DISPLAY 0.617021 (-6440 2685);
PAINT ORANGE (-6440 2685);
FORCEPROP 2 LASTPIN (-6450 2625) $PN G22
J 0
(-6440 2635);
DISPLAY 0.617021 (-6440 2635);
PAINT ORANGE (-6440 2635);
FORCEPROP 2 LASTPIN (-6450 2575) $PN G24
J 0
(-6440 2585);
DISPLAY 0.617021 (-6440 2585);
PAINT ORANGE (-6440 2585);
FORCEPROP 2 LASTPIN (-6450 2525) $PN G26
J 0
(-6440 2535);
DISPLAY 0.617021 (-6440 2535);
PAINT ORANGE (-6440 2535);
FORCEPROP 2 LASTPIN (-6450 2475) $PN G30
J 0
(-6440 2485);
DISPLAY 0.617021 (-6440 2485);
PAINT ORANGE (-6440 2485);
FORCEPROP 2 LASTPIN (-6450 2425) $PN G32
J 0
(-6440 2435);
DISPLAY 0.617021 (-6440 2435);
PAINT ORANGE (-6440 2435);
FORCEPROP 2 LASTPIN (-6450 2375) $PN G36
J 0
(-6440 2385);
DISPLAY 0.617021 (-6440 2385);
PAINT ORANGE (-6440 2385);
FORCEPROP 2 LASTPIN (-6450 2325) $PN G38
J 0
(-6440 2335);
DISPLAY 0.617021 (-6440 2335);
PAINT ORANGE (-6440 2335);
FORCEPROP 2 LASTPIN (-6450 2275) $PN G42
J 0
(-6440 2285);
DISPLAY 0.617021 (-6440 2285);
PAINT ORANGE (-6440 2285);
FORCEPROP 2 LASTPIN (-6450 2225) $PN G66
J 0
(-6440 2235);
DISPLAY 0.617021 (-6440 2235);
PAINT ORANGE (-6440 2235);
FORCEPROP 2 LASTPIN (-6450 2175) $PN G70
J 0
(-6440 2185);
DISPLAY 0.617021 (-6440 2185);
PAINT ORANGE (-6440 2185);
FORCEPROP 2 LASTPIN (-6450 2125) $PN G76
J 0
(-6440 2135);
DISPLAY 0.617021 (-6440 2135);
PAINT ORANGE (-6440 2135);
FORCEPROP 2 LASTPIN (-6450 2075) $PN G78
J 0
(-6440 2085);
DISPLAY 0.617021 (-6440 2085);
PAINT ORANGE (-6440 2085);
FORCEPROP 2 LASTPIN (-6450 2025) $PN G80
J 0
(-6440 2035);
DISPLAY 0.617021 (-6440 2035);
PAINT ORANGE (-6440 2035);
FORCEPROP 2 LASTPIN (-6450 1975) $PN G82
J 0
(-6440 1985);
DISPLAY 0.617021 (-6440 1985);
PAINT ORANGE (-6440 1985);
FORCEPROP 2 LASTPIN (-6450 1925) $PN H3
J 0
(-6440 1935);
DISPLAY 0.617021 (-6440 1935);
PAINT ORANGE (-6440 1935);
FORCEPROP 2 LASTPIN (-6450 1875) $PN H11
J 0
(-6440 1885);
DISPLAY 0.617021 (-6440 1885);
PAINT ORANGE (-6440 1885);
FORCEPROP 2 LASTPIN (-6450 1825) $PN H25
J 0
(-6440 1835);
DISPLAY 0.617021 (-6440 1835);
PAINT ORANGE (-6440 1835);
FORCEPROP 2 LASTPIN (-6450 1775) $PN H27
J 0
(-6440 1785);
DISPLAY 0.617021 (-6440 1785);
PAINT ORANGE (-6440 1785);
FORCEPROP 2 LASTPIN (-6450 1725) $PN H29
J 0
(-6440 1735);
DISPLAY 0.617021 (-6440 1735);
PAINT ORANGE (-6440 1735);
FORCEPROP 2 LASTPIN (-6450 1675) $PN H31
J 0
(-6440 1685);
DISPLAY 0.617021 (-6440 1685);
PAINT ORANGE (-6440 1685);
FORCEPROP 2 LASTPIN (-6450 1575) $PN H35
J 0
(-6440 1585);
DISPLAY 0.617021 (-6440 1585);
PAINT ORANGE (-6440 1585);
FORCEPROP 2 LASTPIN (-6450 1525) $PN H37
J 0
(-6440 1535);
DISPLAY 0.617021 (-6440 1535);
PAINT ORANGE (-6440 1535);
FORCEPROP 2 LASTPIN (-6450 1475) $PN H39
J 0
(-6440 1485);
DISPLAY 0.617021 (-6440 1485);
PAINT ORANGE (-6440 1485);
FORCEPROP 2 LASTPIN (-6450 1425) $PN H41
J 0
(-6440 1435);
DISPLAY 0.617021 (-6440 1435);
PAINT ORANGE (-6440 1435);
FORCEPROP 2 LASTPIN (-6450 1375) $PN H65
J 0
(-6440 1385);
DISPLAY 0.617021 (-6440 1385);
PAINT ORANGE (-6440 1385);
FORCEPROP 2 LASTPIN (-6450 1325) $PN H71
J 0
(-6440 1335);
DISPLAY 0.617021 (-6440 1335);
PAINT ORANGE (-6440 1335);
FORCEPROP 2 LASTPIN (-6450 1275) $PN H75
J 0
(-6440 1285);
DISPLAY 0.617021 (-6440 1285);
PAINT ORANGE (-6440 1285);
FORCEPROP 2 LASTPIN (-6450 1225) $PN DN44
J 0
(-6440 1235);
DISPLAY 0.617021 (-6440 1235);
PAINT ORANGE (-6440 1235);
FORCEPROP 2 LASTPIN (-6450 1175) $PN J4
J 0
(-6440 1185);
DISPLAY 0.617021 (-6440 1185);
PAINT ORANGE (-6440 1185);
FORCEPROP 2 LASTPIN (-6450 1125) $PN J12
J 0
(-6440 1135);
DISPLAY 0.617021 (-6440 1135);
PAINT ORANGE (-6440 1135);
FORCEPROP 2 LASTPIN (-6450 1075) $PN J14
J 0
(-6440 1085);
DISPLAY 0.617021 (-6440 1085);
PAINT ORANGE (-6440 1085);
FORCEPROP 2 LASTPIN (-6450 1025) $PN J22
J 0
(-6440 1035);
DISPLAY 0.617021 (-6440 1035);
PAINT ORANGE (-6440 1035);
FORCEPROP 2 LASTPIN (-6450 975) $PN J26
J 0
(-6440 985);
DISPLAY 0.617021 (-6440 985);
PAINT ORANGE (-6440 985);
FORCEPROP 2 LASTPIN (-6450 925) $PN J28
J 0
(-6440 935);
DISPLAY 0.617021 (-6440 935);
PAINT ORANGE (-6440 935);
FORCEPROP 2 LASTPIN (-6450 875) $PN J32
J 0
(-6440 885);
DISPLAY 0.617021 (-6440 885);
PAINT ORANGE (-6440 885);
FORCEPROP 2 LASTPIN (-6450 825) $PN J34
J 0
(-6440 835);
DISPLAY 0.617021 (-6440 835);
PAINT ORANGE (-6440 835);
FORCEPROP 2 LASTPIN (-6450 775) $PN J38
J 0
(-6440 785);
DISPLAY 0.617021 (-6440 785);
PAINT ORANGE (-6440 785);
FORCEPROP 2 LASTPIN (-6450 725) $PN J40
J 0
(-6440 735);
DISPLAY 0.617021 (-6440 735);
PAINT ORANGE (-6440 735);
FORCEPROP 2 LASTPIN (-6450 675) $PN J72
J 0
(-6440 685);
DISPLAY 0.617021 (-6440 685);
PAINT ORANGE (-6440 685);
FORCEPROP 2 LASTPIN (-6450 625) $PN J74
J 0
(-6440 635);
DISPLAY 0.617021 (-6440 635);
PAINT ORANGE (-6440 635);
FORCEPROP 2 LASTPIN (-6450 2725) $PN G4
J 0
(-6440 2735);
DISPLAY 0.617021 (-6440 2735);
PAINT ORANGE (-6440 2735);
FORCEPROP 2 LASTPIN (-7650 4575) $PN B9
J 2
(-7660 4585);
DISPLAY 0.617021 (-7660 4585);
PAINT ORANGE (-7660 4585);
FORCEPROP 1 LAST PACK_TYPE BGA1
J 0
(-7600 4875);
PAINT SKYBLUE (-7600 4875);
DISPLAY INVISIBLE (-7600 4875);
FORCEPROP 2 LAST SEC_TYPE BGA1
J 0
(-7600 4875);
DISPLAY 1.021277 (-7600 4875);
PAINT ORANGE (-7600 4875);
DISPLAY INVISIBLE (-7600 4875);
FORCEPROP 2 LAST CDS_LIB chpset_lib
J 0
(-7050 2575);
PAINT ORANGE (-7050 2575);
DISPLAY INVISIBLE (-7050 2575);
FORCEPROP 2 LAST SEC 23
J 0
(-7600 4875);
DISPLAY 0.680851 (-7600 4875);
PAINT MONO (-7600 4875);
DISPLAY INVISIBLE (-7600 4875);
FORCEPROP 2 LAST CDS_LOCATION U5D1
J 0
(-7600 4825);
DISPLAY 0.617021 (-7600 4825);
PAINT AQUA (-7600 4825);
DISPLAY INVISIBLE (-7600 4825);
FORCEPROP 1 LAST PATH I20
J 0
(-7050 4775);
PAINT GREEN (-7050 4775);
DISPLAY INVISIBLE (-7050 4775);
FORCEPROP 0 LAST ROOM CPU0
J 0
(-7600 4925);
DISPLAY 1.021277 (-7600 4925);
PAINT ORANGE (-7600 4925);
DISPLAY INVISIBLE (-7600 4925);
FORCEADD SKX_EXT_B..24
(-5225 2575);
FORCEPROP 1 LAST LOCATION U5D1
J 0
(-5775 4825);
DISPLAY 0.617021 (-5775 4825);
PAINT AQUA (-5775 4825);
FORCEPROP 1 LAST PART_NUMBER TBD
J 0
(-5775 425);
DISPLAY 0.617021 (-5775 425);
PAINT BLUE (-5775 425);
FORCEPROP 1 LAST MATERIAL IC
J 0
(-5775 4775);
DISPLAY 0.617021 (-5775 4775);
PAINT SKYBLUE (-5775 4775);
FORCEPROP 2 LASTPIN (-5825 4575) $PN J76
J 2
(-5835 4585);
DISPLAY 0.617021 (-5835 4585);
PAINT ORANGE (-5835 4585);
FORCEPROP 2 LASTPIN (-5825 4525) $PN J82
J 2
(-5835 4535);
DISPLAY 0.617021 (-5835 4535);
PAINT ORANGE (-5835 4535);
FORCEPROP 2 LASTPIN (-5825 4475) $PN J84
J 2
(-5835 4485);
DISPLAY 0.617021 (-5835 4485);
PAINT ORANGE (-5835 4485);
FORCEPROP 2 LASTPIN (-5825 4425) $PN K1
J 2
(-5835 4435);
DISPLAY 0.617021 (-5835 4435);
PAINT ORANGE (-5835 4435);
FORCEPROP 2 LASTPIN (-5825 4375) $PN K11
J 2
(-5835 4385);
DISPLAY 0.617021 (-5835 4385);
PAINT ORANGE (-5835 4385);
FORCEPROP 2 LASTPIN (-5825 4325) $PN K13
J 2
(-5835 4335);
DISPLAY 0.617021 (-5835 4335);
PAINT ORANGE (-5835 4335);
FORCEPROP 2 LASTPIN (-5825 4275) $PN K17
J 2
(-5835 4285);
DISPLAY 0.617021 (-5835 4285);
PAINT ORANGE (-5835 4285);
FORCEPROP 2 LASTPIN (-5825 4225) $PN DB7
J 2
(-5835 4235);
DISPLAY 0.617021 (-5835 4235);
PAINT ORANGE (-5835 4235);
FORCEPROP 2 LASTPIN (-5825 4175) $PN K27
J 2
(-5835 4185);
DISPLAY 0.617021 (-5835 4185);
PAINT ORANGE (-5835 4185);
FORCEPROP 2 LASTPIN (-5825 4125) $PN K33
J 2
(-5835 4135);
DISPLAY 0.617021 (-5835 4135);
PAINT ORANGE (-5835 4135);
FORCEPROP 2 LASTPIN (-5825 4075) $PN K39
J 2
(-5835 4085);
DISPLAY 0.617021 (-5835 4085);
PAINT ORANGE (-5835 4085);
FORCEPROP 2 LASTPIN (-5825 4025) $PN K65
J 2
(-5835 4035);
DISPLAY 0.617021 (-5835 4035);
PAINT ORANGE (-5835 4035);
FORCEPROP 2 LASTPIN (-5825 3975) $PN K67
J 2
(-5835 3985);
DISPLAY 0.617021 (-5835 3985);
PAINT ORANGE (-5835 3985);
FORCEPROP 2 LASTPIN (-5825 3925) $PN K69
J 2
(-5835 3935);
DISPLAY 0.617021 (-5835 3935);
PAINT ORANGE (-5835 3935);
FORCEPROP 2 LASTPIN (-5825 3875) $PN K71
J 2
(-5835 3885);
DISPLAY 0.617021 (-5835 3885);
PAINT ORANGE (-5835 3885);
FORCEPROP 2 LASTPIN (-5825 3825) $PN K73
J 2
(-5835 3835);
DISPLAY 0.617021 (-5835 3835);
PAINT ORANGE (-5835 3835);
FORCEPROP 2 LASTPIN (-5825 3775) $PN K77
J 2
(-5835 3785);
DISPLAY 0.617021 (-5835 3785);
PAINT ORANGE (-5835 3785);
FORCEPROP 2 LASTPIN (-5825 3725) $PN K81
J 2
(-5835 3735);
DISPLAY 0.617021 (-5835 3735);
PAINT ORANGE (-5835 3735);
FORCEPROP 2 LASTPIN (-5825 3675) $PN K83
J 2
(-5835 3685);
DISPLAY 0.617021 (-5835 3685);
PAINT ORANGE (-5835 3685);
FORCEPROP 2 LASTPIN (-5825 3625) $PN K85
J 2
(-5835 3635);
DISPLAY 0.617021 (-5835 3635);
PAINT ORANGE (-5835 3635);
FORCEPROP 2 LASTPIN (-5825 3575) $PN L10
J 2
(-5835 3585);
DISPLAY 0.617021 (-5835 3585);
PAINT ORANGE (-5835 3585);
FORCEPROP 2 LASTPIN (-5825 3525) $PN L2
J 2
(-5835 3535);
DISPLAY 0.617021 (-5835 3535);
PAINT ORANGE (-5835 3535);
FORCEPROP 2 LASTPIN (-5825 3475) $PN L6
J 2
(-5835 3485);
DISPLAY 0.617021 (-5835 3485);
PAINT ORANGE (-5835 3485);
FORCEPROP 2 LASTPIN (-5825 3425) $PN L20
J 2
(-5835 3435);
DISPLAY 0.617021 (-5835 3435);
PAINT ORANGE (-5835 3435);
FORCEPROP 2 LASTPIN (-5825 3375) $PN L22
J 2
(-5835 3385);
DISPLAY 0.617021 (-5835 3385);
PAINT ORANGE (-5835 3385);
FORCEPROP 2 LASTPIN (-5825 3325) $PN L72
J 2
(-5835 3335);
DISPLAY 0.617021 (-5835 3335);
PAINT ORANGE (-5835 3335);
FORCEPROP 2 LASTPIN (-5825 3275) $PN L78
J 2
(-5835 3285);
DISPLAY 0.617021 (-5835 3285);
PAINT ORANGE (-5835 3285);
FORCEPROP 2 LASTPIN (-5825 3225) $PN L80
J 2
(-5835 3235);
DISPLAY 0.617021 (-5835 3235);
PAINT ORANGE (-5835 3235);
FORCEPROP 2 LASTPIN (-5825 3175) $PN L82
J 2
(-5835 3185);
DISPLAY 0.617021 (-5835 3185);
PAINT ORANGE (-5835 3185);
FORCEPROP 2 LASTPIN (-5825 3125) $PN BT9
J 2
(-5835 3135);
DISPLAY 0.617021 (-5835 3135);
PAINT ORANGE (-5835 3135);
FORCEPROP 2 LASTPIN (-5825 3075) $PN CT7
J 2
(-5835 3085);
DISPLAY 0.617021 (-5835 3085);
PAINT ORANGE (-5835 3085);
FORCEPROP 2 LASTPIN (-5825 3025) $PN M15
J 2
(-5835 3035);
DISPLAY 0.617021 (-5835 3035);
PAINT ORANGE (-5835 3035);
FORCEPROP 2 LASTPIN (-5825 2975) $PN M17
J 2
(-5835 2985);
DISPLAY 0.617021 (-5835 2985);
PAINT ORANGE (-5835 2985);
FORCEPROP 2 LASTPIN (-5825 2925) $PN M19
J 2
(-5835 2935);
DISPLAY 0.617021 (-5835 2935);
PAINT ORANGE (-5835 2935);
FORCEPROP 2 LASTPIN (-5825 2875) $PN M23
J 2
(-5835 2885);
DISPLAY 0.617021 (-5835 2885);
PAINT ORANGE (-5835 2885);
FORCEPROP 2 LASTPIN (-5825 2825) $PN M25
J 2
(-5835 2835);
DISPLAY 0.617021 (-5835 2835);
PAINT ORANGE (-5835 2835);
FORCEPROP 2 LASTPIN (-5825 2775) $PN M27
J 2
(-5835 2785);
DISPLAY 0.617021 (-5835 2785);
PAINT ORANGE (-5835 2785);
FORCEPROP 2 LASTPIN (-5825 2725) $PN M29
J 2
(-5835 2735);
DISPLAY 0.617021 (-5835 2735);
PAINT ORANGE (-5835 2735);
FORCEPROP 2 LASTPIN (-5825 2675) $PN M31
J 2
(-5835 2685);
DISPLAY 0.617021 (-5835 2685);
PAINT ORANGE (-5835 2685);
FORCEPROP 2 LASTPIN (-5825 2625) $PN M33
J 2
(-5835 2635);
DISPLAY 0.617021 (-5835 2635);
PAINT ORANGE (-5835 2635);
FORCEPROP 2 LASTPIN (-5825 2575) $PN M35
J 2
(-5835 2585);
DISPLAY 0.617021 (-5835 2585);
PAINT ORANGE (-5835 2585);
FORCEPROP 2 LASTPIN (-5825 2525) $PN M37
J 2
(-5835 2535);
DISPLAY 0.617021 (-5835 2535);
PAINT ORANGE (-5835 2535);
FORCEPROP 2 LASTPIN (-5825 2475) $PN M39
J 2
(-5835 2485);
DISPLAY 0.617021 (-5835 2485);
PAINT ORANGE (-5835 2485);
FORCEPROP 2 LASTPIN (-5825 2425) $PN M41
J 2
(-5835 2435);
DISPLAY 0.617021 (-5835 2435);
PAINT ORANGE (-5835 2435);
FORCEPROP 2 LASTPIN (-5825 2375) $PN M43
J 2
(-5835 2385);
DISPLAY 0.617021 (-5835 2385);
PAINT ORANGE (-5835 2385);
FORCEPROP 2 LASTPIN (-5825 2325) $PN M65
J 2
(-5835 2335);
DISPLAY 0.617021 (-5835 2335);
PAINT ORANGE (-5835 2335);
FORCEPROP 2 LASTPIN (-5825 2275) $PN M71
J 2
(-5835 2285);
DISPLAY 0.617021 (-5835 2285);
PAINT ORANGE (-5835 2285);
FORCEPROP 2 LASTPIN (-5825 2225) $PN M79
J 2
(-5835 2235);
DISPLAY 0.617021 (-5835 2235);
PAINT ORANGE (-5835 2235);
FORCEPROP 2 LASTPIN (-5825 2175) $PN M83
J 2
(-5835 2185);
DISPLAY 0.617021 (-5835 2185);
PAINT ORANGE (-5835 2185);
FORCEPROP 2 LASTPIN (-5825 2125) $PN M85
J 2
(-5835 2135);
DISPLAY 0.617021 (-5835 2135);
PAINT ORANGE (-5835 2135);
FORCEPROP 2 LASTPIN (-5825 2075) $PN DM19
J 2
(-5835 2085);
DISPLAY 0.617021 (-5835 2085);
PAINT ORANGE (-5835 2085);
FORCEPROP 2 LASTPIN (-5825 2025) $PN N20
J 2
(-5835 2035);
DISPLAY 0.617021 (-5835 2035);
PAINT ORANGE (-5835 2035);
FORCEPROP 2 LASTPIN (-5825 1975) $PN N22
J 2
(-5835 1985);
DISPLAY 0.617021 (-5835 1985);
PAINT ORANGE (-5835 1985);
FORCEPROP 2 LASTPIN (-5825 1925) $PN N6
J 2
(-5835 1935);
DISPLAY 0.617021 (-5835 1935);
PAINT ORANGE (-5835 1935);
FORCEPROP 2 LASTPIN (-5825 1875) $PN N66
J 2
(-5835 1885);
DISPLAY 0.617021 (-5835 1885);
PAINT ORANGE (-5835 1885);
FORCEPROP 2 LASTPIN (-5825 1825) $PN N70
J 2
(-5835 1835);
DISPLAY 0.617021 (-5835 1835);
PAINT ORANGE (-5835 1835);
FORCEPROP 2 LASTPIN (-5825 1775) $PN N72
J 2
(-5835 1785);
DISPLAY 0.617021 (-5835 1785);
PAINT ORANGE (-5835 1785);
FORCEPROP 2 LASTPIN (-5825 1725) $PN N74
J 2
(-5835 1735);
DISPLAY 0.617021 (-5835 1735);
PAINT ORANGE (-5835 1735);
FORCEPROP 2 LASTPIN (-5825 1675) $PN N76
J 2
(-5835 1685);
DISPLAY 0.617021 (-5835 1685);
PAINT ORANGE (-5835 1685);
FORCEPROP 2 LASTPIN (-5825 1625) $PN N78
J 2
(-5835 1635);
DISPLAY 0.617021 (-5835 1635);
PAINT ORANGE (-5835 1635);
FORCEPROP 2 LASTPIN (-5825 1575) $PN N4
J 2
(-5835 1585);
DISPLAY 0.617021 (-5835 1585);
PAINT ORANGE (-5835 1585);
FORCEPROP 2 LASTPIN (-5825 1525) $PN N8
J 2
(-5835 1535);
DISPLAY 0.617021 (-5835 1535);
PAINT ORANGE (-5835 1535);
FORCEPROP 2 LASTPIN (-5825 1475) $PN P11
J 2
(-5835 1485);
DISPLAY 0.617021 (-5835 1485);
PAINT ORANGE (-5835 1485);
FORCEPROP 2 LASTPIN (-5825 1425) $PN P15
J 2
(-5835 1435);
DISPLAY 0.617021 (-5835 1435);
PAINT ORANGE (-5835 1435);
FORCEPROP 2 LASTPIN (-5825 1375) $PN P27
J 2
(-5835 1385);
DISPLAY 0.617021 (-5835 1385);
PAINT ORANGE (-5835 1385);
FORCEPROP 2 LASTPIN (-5825 1325) $PN P33
J 2
(-5835 1335);
DISPLAY 0.617021 (-5835 1335);
PAINT ORANGE (-5835 1335);
FORCEPROP 2 LASTPIN (-5825 1275) $PN P39
J 2
(-5835 1285);
DISPLAY 0.617021 (-5835 1285);
PAINT ORANGE (-5835 1285);
FORCEPROP 2 LASTPIN (-5825 1225) $PN P67
J 2
(-5835 1235);
DISPLAY 0.617021 (-5835 1235);
PAINT ORANGE (-5835 1235);
FORCEPROP 2 LASTPIN (-5825 1175) $PN P69
J 2
(-5835 1185);
DISPLAY 0.617021 (-5835 1185);
PAINT ORANGE (-5835 1185);
FORCEPROP 2 LASTPIN (-5825 1125) $PN P71
J 2
(-5835 1135);
DISPLAY 0.617021 (-5835 1135);
PAINT ORANGE (-5835 1135);
FORCEPROP 2 LASTPIN (-5825 1075) $PN P81
J 2
(-5835 1085);
DISPLAY 0.617021 (-5835 1085);
PAINT ORANGE (-5835 1085);
FORCEPROP 2 LASTPIN (-5825 1025) $PN P83
J 2
(-5835 1035);
DISPLAY 0.617021 (-5835 1035);
PAINT ORANGE (-5835 1035);
FORCEPROP 2 LASTPIN (-5825 975) $PN R14
J 2
(-5835 985);
DISPLAY 0.617021 (-5835 985);
PAINT ORANGE (-5835 985);
FORCEPROP 2 LASTPIN (-5825 925) $PN R18
J 2
(-5835 935);
DISPLAY 0.617021 (-5835 935);
PAINT ORANGE (-5835 935);
FORCEPROP 2 LASTPIN (-5825 875) $PN R2
J 2
(-5835 885);
DISPLAY 0.617021 (-5835 885);
PAINT ORANGE (-5835 885);
FORCEPROP 2 LASTPIN (-5825 825) $PN R4
J 2
(-5835 835);
DISPLAY 0.617021 (-5835 835);
PAINT ORANGE (-5835 835);
FORCEPROP 2 LASTPIN (-5825 775) $PN R22
J 2
(-5835 785);
DISPLAY 0.617021 (-5835 785);
PAINT ORANGE (-5835 785);
FORCEPROP 2 LASTPIN (-5825 725) $PN R26
J 2
(-5835 735);
DISPLAY 0.617021 (-5835 735);
PAINT ORANGE (-5835 735);
FORCEPROP 2 LASTPIN (-5825 675) $PN R28
J 2
(-5835 685);
DISPLAY 0.617021 (-5835 685);
PAINT ORANGE (-5835 685);
FORCEPROP 2 LASTPIN (-5825 625) $PN R32
J 2
(-5835 635);
DISPLAY 0.617021 (-5835 635);
PAINT ORANGE (-5835 635);
FORCEPROP 2 LASTPIN (-4625 4575) $PN R34
J 0
(-4615 4585);
DISPLAY 0.617021 (-4615 4585);
PAINT ORANGE (-4615 4585);
FORCEPROP 2 LASTPIN (-4625 4525) $PN R38
J 0
(-4615 4535);
DISPLAY 0.617021 (-4615 4535);
PAINT ORANGE (-4615 4535);
FORCEPROP 2 LASTPIN (-4625 4475) $PN R40
J 0
(-4615 4485);
DISPLAY 0.617021 (-4615 4485);
PAINT ORANGE (-4615 4485);
FORCEPROP 2 LASTPIN (-4625 4425) $PN R68
J 0
(-4615 4435);
DISPLAY 0.617021 (-4615 4435);
PAINT ORANGE (-4615 4435);
FORCEPROP 2 LASTPIN (-4625 4375) $PN R72
J 0
(-4615 4385);
DISPLAY 0.617021 (-4615 4385);
PAINT ORANGE (-4615 4385);
FORCEPROP 2 LASTPIN (-4625 4325) $PN R78
J 0
(-4615 4335);
DISPLAY 0.617021 (-4615 4335);
PAINT ORANGE (-4615 4335);
FORCEPROP 2 LASTPIN (-4625 4275) $PN R86
J 0
(-4615 4285);
DISPLAY 0.617021 (-4615 4285);
PAINT ORANGE (-4615 4285);
FORCEPROP 2 LASTPIN (-4625 4225) $PN T13
J 0
(-4615 4235);
DISPLAY 0.617021 (-4615 4235);
PAINT ORANGE (-4615 4235);
FORCEPROP 2 LASTPIN (-4625 4175) $PN T17
J 0
(-4615 4185);
DISPLAY 0.617021 (-4615 4185);
PAINT ORANGE (-4615 4185);
FORCEPROP 2 LASTPIN (-4625 4125) $PN T25
J 0
(-4615 4135);
DISPLAY 0.617021 (-4615 4135);
PAINT ORANGE (-4615 4135);
FORCEPROP 2 LASTPIN (-4625 4075) $PN T29
J 0
(-4615 4085);
DISPLAY 0.617021 (-4615 4085);
PAINT ORANGE (-4615 4085);
FORCEPROP 2 LASTPIN (-4625 4025) $PN T31
J 0
(-4615 4035);
DISPLAY 0.617021 (-4615 4035);
PAINT ORANGE (-4615 4035);
FORCEPROP 2 LASTPIN (-4625 3975) $PN T35
J 0
(-4615 3985);
DISPLAY 0.617021 (-4615 3985);
PAINT ORANGE (-4615 3985);
FORCEPROP 2 LASTPIN (-4625 3925) $PN T37
J 0
(-4615 3935);
DISPLAY 0.617021 (-4615 3935);
PAINT ORANGE (-4615 3935);
FORCEPROP 2 LASTPIN (-4625 3875) $PN T41
J 0
(-4615 3885);
DISPLAY 0.617021 (-4615 3885);
PAINT ORANGE (-4615 3885);
FORCEPROP 2 LASTPIN (-4625 3825) $PN T65
J 0
(-4615 3835);
DISPLAY 0.617021 (-4615 3835);
PAINT ORANGE (-4615 3835);
FORCEPROP 2 LASTPIN (-4625 3775) $PN T73
J 0
(-4615 3785);
DISPLAY 0.617021 (-4615 3785);
PAINT ORANGE (-4615 3785);
FORCEPROP 2 LASTPIN (-4625 3725) $PN T77
J 0
(-4615 3735);
DISPLAY 0.617021 (-4615 3735);
PAINT ORANGE (-4615 3735);
FORCEPROP 2 LASTPIN (-4625 3675) $PN T83
J 0
(-4615 3685);
DISPLAY 0.617021 (-4615 3685);
PAINT ORANGE (-4615 3685);
FORCEPROP 2 LASTPIN (-4625 3625) $PN T85
J 0
(-4615 3635);
DISPLAY 0.617021 (-4615 3635);
PAINT ORANGE (-4615 3635);
FORCEPROP 2 LASTPIN (-4625 3575) $PN U2
J 0
(-4615 3585);
DISPLAY 0.617021 (-4615 3585);
PAINT ORANGE (-4615 3585);
FORCEPROP 2 LASTPIN (-4625 3525) $PN U4
J 0
(-4615 3535);
DISPLAY 0.617021 (-4615 3535);
PAINT ORANGE (-4615 3535);
FORCEPROP 2 LASTPIN (-4625 3475) $PN U6
J 0
(-4615 3485);
DISPLAY 0.617021 (-4615 3485);
PAINT ORANGE (-4615 3485);
FORCEPROP 2 LASTPIN (-4625 3425) $PN U20
J 0
(-4615 3435);
DISPLAY 0.617021 (-4615 3435);
PAINT ORANGE (-4615 3435);
FORCEPROP 2 LASTPIN (-4625 3375) $PN U22
J 0
(-4615 3385);
DISPLAY 0.617021 (-4615 3385);
PAINT ORANGE (-4615 3385);
FORCEPROP 2 LASTPIN (-4625 3325) $PN U24
J 0
(-4615 3335);
DISPLAY 0.617021 (-4615 3335);
PAINT ORANGE (-4615 3335);
FORCEPROP 2 LASTPIN (-4625 3275) $PN U30
J 0
(-4615 3285);
DISPLAY 0.617021 (-4615 3285);
PAINT ORANGE (-4615 3285);
FORCEPROP 2 LASTPIN (-4625 3225) $PN U36
J 0
(-4615 3235);
DISPLAY 0.617021 (-4615 3235);
PAINT ORANGE (-4615 3235);
FORCEPROP 2 LASTPIN (-4625 3175) $PN U42
J 0
(-4615 3185);
DISPLAY 0.617021 (-4615 3185);
PAINT ORANGE (-4615 3185);
FORCEPROP 2 LASTPIN (-4625 3125) $PN U68
J 0
(-4615 3135);
DISPLAY 0.617021 (-4615 3135);
PAINT ORANGE (-4615 3135);
FORCEPROP 2 LASTPIN (-4625 3075) $PN U70
J 0
(-4615 3085);
DISPLAY 0.617021 (-4615 3085);
PAINT ORANGE (-4615 3085);
FORCEPROP 2 LASTPIN (-4625 3025) $PN U74
J 0
(-4615 3035);
DISPLAY 0.617021 (-4615 3035);
PAINT ORANGE (-4615 3035);
FORCEPROP 2 LASTPIN (-4625 2975) $PN U76
J 0
(-4615 2985);
DISPLAY 0.617021 (-4615 2985);
PAINT ORANGE (-4615 2985);
FORCEPROP 2 LASTPIN (-4625 2925) $PN U78
J 0
(-4615 2935);
DISPLAY 0.617021 (-4615 2935);
PAINT ORANGE (-4615 2935);
FORCEPROP 2 LASTPIN (-4625 2875) $PN U80
J 0
(-4615 2885);
DISPLAY 0.617021 (-4615 2885);
PAINT ORANGE (-4615 2885);
FORCEPROP 2 LASTPIN (-4625 2825) $PN U86
J 0
(-4615 2835);
DISPLAY 0.617021 (-4615 2835);
PAINT ORANGE (-4615 2835);
FORCEPROP 2 LASTPIN (-4625 2775) $PN V1
J 0
(-4615 2785);
DISPLAY 0.617021 (-4615 2785);
PAINT ORANGE (-4615 2785);
FORCEPROP 2 LASTPIN (-4625 2725) $PN V5
J 0
(-4615 2735);
DISPLAY 0.617021 (-4615 2735);
PAINT ORANGE (-4615 2735);
FORCEPROP 2 LASTPIN (-4625 2675) $PN V9
J 0
(-4615 2685);
DISPLAY 0.617021 (-4615 2685);
PAINT ORANGE (-4615 2685);
FORCEPROP 2 LASTPIN (-4625 2625) $PN V13
J 0
(-4615 2635);
DISPLAY 0.617021 (-4615 2635);
PAINT ORANGE (-4615 2635);
FORCEPROP 2 LASTPIN (-4625 2575) $PN V15
J 0
(-4615 2585);
DISPLAY 0.617021 (-4615 2585);
PAINT ORANGE (-4615 2585);
FORCEPROP 2 LASTPIN (-4625 2525) $PN V21
J 0
(-4615 2535);
DISPLAY 0.617021 (-4615 2535);
PAINT ORANGE (-4615 2535);
FORCEPROP 2 LASTPIN (-4625 2475) $PN V23
J 0
(-4615 2485);
DISPLAY 0.617021 (-4615 2485);
PAINT ORANGE (-4615 2485);
FORCEPROP 2 LASTPIN (-4625 2425) $PN V43
J 0
(-4615 2435);
DISPLAY 0.617021 (-4615 2435);
PAINT ORANGE (-4615 2435);
FORCEPROP 2 LASTPIN (-4625 2375) $PN V73
J 0
(-4615 2385);
DISPLAY 0.617021 (-4615 2385);
PAINT ORANGE (-4615 2385);
FORCEPROP 2 LASTPIN (-4625 2325) $PN V75
J 0
(-4615 2335);
DISPLAY 0.617021 (-4615 2335);
PAINT ORANGE (-4615 2335);
FORCEPROP 2 LASTPIN (-4625 2275) $PN V77
J 0
(-4615 2285);
DISPLAY 0.617021 (-4615 2285);
PAINT ORANGE (-4615 2285);
FORCEPROP 2 LASTPIN (-4625 2225) $PN V83
J 0
(-4615 2235);
DISPLAY 0.617021 (-4615 2235);
PAINT ORANGE (-4615 2235);
FORCEPROP 2 LASTPIN (-4625 2175) $PN W8
J 0
(-4615 2185);
DISPLAY 0.617021 (-4615 2185);
PAINT ORANGE (-4615 2185);
FORCEPROP 2 LASTPIN (-4625 2125) $PN AC56
J 0
(-4615 2135);
DISPLAY 0.617021 (-4615 2135);
PAINT ORANGE (-4615 2135);
FORCEPROP 2 LASTPIN (-4625 2075) $PN W12
J 0
(-4615 2085);
DISPLAY 0.617021 (-4615 2085);
PAINT ORANGE (-4615 2085);
FORCEPROP 2 LASTPIN (-4625 2025) $PN W22
J 0
(-4615 2035);
DISPLAY 0.617021 (-4615 2035);
PAINT ORANGE (-4615 2035);
FORCEPROP 2 LASTPIN (-4625 1975) $PN W24
J 0
(-4615 1985);
DISPLAY 0.617021 (-4615 1985);
PAINT ORANGE (-4615 1985);
FORCEPROP 2 LASTPIN (-4625 1925) $PN W26
J 0
(-4615 1935);
DISPLAY 0.617021 (-4615 1935);
PAINT ORANGE (-4615 1935);
FORCEPROP 2 LASTPIN (-4625 1875) $PN W28
J 0
(-4615 1885);
DISPLAY 0.617021 (-4615 1885);
PAINT ORANGE (-4615 1885);
FORCEPROP 2 LASTPIN (-4625 1825) $PN W30
J 0
(-4615 1835);
DISPLAY 0.617021 (-4615 1835);
PAINT ORANGE (-4615 1835);
FORCEPROP 2 LASTPIN (-4625 1775) $PN W32
J 0
(-4615 1785);
DISPLAY 0.617021 (-4615 1785);
PAINT ORANGE (-4615 1785);
FORCEPROP 2 LASTPIN (-4625 1725) $PN W34
J 0
(-4615 1735);
DISPLAY 0.617021 (-4615 1735);
PAINT ORANGE (-4615 1735);
FORCEPROP 2 LASTPIN (-4625 1675) $PN W36
J 0
(-4615 1685);
DISPLAY 0.617021 (-4615 1685);
PAINT ORANGE (-4615 1685);
FORCEPROP 2 LASTPIN (-4625 1625) $PN W38
J 0
(-4615 1635);
DISPLAY 0.617021 (-4615 1635);
PAINT ORANGE (-4615 1635);
FORCEPROP 2 LASTPIN (-4625 1575) $PN W40
J 0
(-4615 1585);
DISPLAY 0.617021 (-4615 1585);
PAINT ORANGE (-4615 1585);
FORCEPROP 2 LASTPIN (-4625 1525) $PN W42
J 0
(-4615 1535);
DISPLAY 0.617021 (-4615 1535);
PAINT ORANGE (-4615 1535);
FORCEPROP 2 LASTPIN (-4625 1475) $PN W68
J 0
(-4615 1485);
DISPLAY 0.617021 (-4615 1485);
PAINT ORANGE (-4615 1485);
FORCEPROP 2 LASTPIN (-4625 1425) $PN W74
J 0
(-4615 1435);
DISPLAY 0.617021 (-4615 1435);
PAINT ORANGE (-4615 1435);
FORCEPROP 2 LASTPIN (-4625 1375) $PN W78
J 0
(-4615 1385);
DISPLAY 0.617021 (-4615 1385);
PAINT ORANGE (-4615 1385);
FORCEPROP 2 LASTPIN (-4625 1325) $PN W82
J 0
(-4615 1335);
DISPLAY 0.617021 (-4615 1335);
PAINT ORANGE (-4615 1335);
FORCEPROP 2 LASTPIN (-4625 1275) $PN Y15
J 0
(-4615 1285);
DISPLAY 0.617021 (-4615 1285);
PAINT ORANGE (-4615 1285);
FORCEPROP 2 LASTPIN (-4625 1225) $PN Y17
J 0
(-4615 1235);
DISPLAY 0.617021 (-4615 1235);
PAINT ORANGE (-4615 1235);
FORCEPROP 2 LASTPIN (-4625 1175) $PN Y5
J 0
(-4615 1185);
DISPLAY 0.617021 (-4615 1185);
PAINT ORANGE (-4615 1185);
FORCEPROP 2 LASTPIN (-4625 1125) $PN Y67
J 0
(-4615 1135);
DISPLAY 0.617021 (-4615 1135);
PAINT ORANGE (-4615 1135);
FORCEPROP 2 LASTPIN (-4625 1075) $PN Y7
J 0
(-4615 1085);
DISPLAY 0.617021 (-4615 1085);
PAINT ORANGE (-4615 1085);
FORCEPROP 2 LASTPIN (-4625 1025) $PN Y9
J 0
(-4615 1035);
DISPLAY 0.617021 (-4615 1035);
PAINT ORANGE (-4615 1035);
FORCEPROP 2 LASTPIN (-4625 975) $PN Y71
J 0
(-4615 985);
DISPLAY 0.617021 (-4615 985);
PAINT ORANGE (-4615 985);
FORCEPROP 2 LASTPIN (-4625 925) $PN Y73
J 0
(-4615 935);
DISPLAY 0.617021 (-4615 935);
PAINT ORANGE (-4615 935);
FORCEPROP 2 LASTPIN (-4625 875) $PN Y79
J 0
(-4615 885);
DISPLAY 0.617021 (-4615 885);
PAINT ORANGE (-4615 885);
FORCEPROP 2 LASTPIN (-4625 825) $PN Y81
J 0
(-4615 835);
DISPLAY 0.617021 (-4615 835);
PAINT ORANGE (-4615 835);
FORCEPROP 2 LASTPIN (-4625 775) $PN Y83
J 0
(-4615 785);
DISPLAY 0.617021 (-4615 785);
PAINT ORANGE (-4615 785);
FORCEPROP 2 LASTPIN (-4625 725) $PN Y85
J 0
(-4615 735);
DISPLAY 0.617021 (-4615 735);
PAINT ORANGE (-4615 735);
FORCEPROP 2 LASTPIN (-4625 675) $PN AA4
J 0
(-4615 685);
DISPLAY 0.617021 (-4615 685);
PAINT ORANGE (-4615 685);
FORCEPROP 2 LASTPIN (-4625 625) $PN AA16
J 0
(-4615 635);
DISPLAY 0.617021 (-4615 635);
PAINT ORANGE (-4615 635);
FORCEPROP 1 LAST PACK_TYPE BGA1
J 0
(-5775 4875);
PAINT SKYBLUE (-5775 4875);
DISPLAY INVISIBLE (-5775 4875);
FORCEPROP 2 LAST SEC_TYPE BGA1
J 0
(-5775 4875);
DISPLAY 1.021277 (-5775 4875);
PAINT ORANGE (-5775 4875);
DISPLAY INVISIBLE (-5775 4875);
FORCEPROP 2 LAST CDS_LIB chpset_lib
J 0
(-5225 2575);
PAINT ORANGE (-5225 2575);
DISPLAY INVISIBLE (-5225 2575);
FORCEPROP 2 LAST SEC 24
J 0
(-5775 4875);
DISPLAY 0.680851 (-5775 4875);
PAINT MONO (-5775 4875);
DISPLAY INVISIBLE (-5775 4875);
FORCEPROP 2 LAST CDS_LOCATION U5D1
J 0
(-5775 4825);
DISPLAY 0.617021 (-5775 4825);
PAINT AQUA (-5775 4825);
DISPLAY INVISIBLE (-5775 4825);
FORCEPROP 1 LAST PATH I21
J 0
(-5225 4775);
PAINT GREEN (-5225 4775);
DISPLAY INVISIBLE (-5225 4775);
FORCEPROP 0 LAST ROOM CPU0
J 0
(-5775 4925);
DISPLAY 1.021277 (-5775 4925);
PAINT ORANGE (-5775 4925);
DISPLAY INVISIBLE (-5775 4925);
FORCEADD SKX_EXT_B..25
(-3400 2575);
FORCEPROP 1 LAST LOCATION U5D1
J 0
(-3950 4825);
DISPLAY 0.617021 (-3950 4825);
PAINT AQUA (-3950 4825);
FORCEPROP 1 LAST PART_NUMBER TBD
J 0
(-3950 425);
DISPLAY 0.617021 (-3950 425);
PAINT BLUE (-3950 425);
FORCEPROP 1 LAST MATERIAL IC
J 0
(-3950 4775);
DISPLAY 0.617021 (-3950 4775);
PAINT SKYBLUE (-3950 4775);
FORCEPROP 2 LASTPIN (-4000 4575) $PN AA18
J 2
(-4010 4585);
DISPLAY 0.617021 (-4010 4585);
PAINT ORANGE (-4010 4585);
FORCEPROP 2 LASTPIN (-4000 4525) $PN AA22
J 2
(-4010 4535);
DISPLAY 0.617021 (-4010 4535);
PAINT ORANGE (-4010 4535);
FORCEPROP 2 LASTPIN (-4000 4475) $PN AA24
J 2
(-4010 4485);
DISPLAY 0.617021 (-4010 4485);
PAINT ORANGE (-4010 4485);
FORCEPROP 2 LASTPIN (-4000 4425) $PN AA30
J 2
(-4010 4435);
DISPLAY 0.617021 (-4010 4435);
PAINT ORANGE (-4010 4435);
FORCEPROP 2 LASTPIN (-4000 4375) $PN AA36
J 2
(-4010 4385);
DISPLAY 0.617021 (-4010 4385);
PAINT ORANGE (-4010 4385);
FORCEPROP 2 LASTPIN (-4000 4325) $PN AA42
J 2
(-4010 4335);
DISPLAY 0.617021 (-4010 4335);
PAINT ORANGE (-4010 4335);
FORCEPROP 2 LASTPIN (-4000 4275) $PN AA64
J 2
(-4010 4285);
DISPLAY 0.617021 (-4010 4285);
PAINT ORANGE (-4010 4285);
FORCEPROP 2 LASTPIN (-4000 4225) $PN AA66
J 2
(-4010 4235);
DISPLAY 0.617021 (-4010 4235);
PAINT ORANGE (-4010 4235);
FORCEPROP 2 LASTPIN (-4000 4175) $PN AA68
J 2
(-4010 4185);
DISPLAY 0.617021 (-4010 4185);
PAINT ORANGE (-4010 4185);
FORCEPROP 2 LASTPIN (-4000 4125) $PN AA76
J 2
(-4010 4135);
DISPLAY 0.617021 (-4010 4135);
PAINT ORANGE (-4010 4135);
FORCEPROP 2 LASTPIN (-4000 4075) $PN AA78
J 2
(-4010 4085);
DISPLAY 0.617021 (-4010 4085);
PAINT ORANGE (-4010 4085);
FORCEPROP 2 LASTPIN (-4000 4025) $PN AA80
J 2
(-4010 4035);
DISPLAY 0.617021 (-4010 4035);
PAINT ORANGE (-4010 4035);
FORCEPROP 2 LASTPIN (-4000 3975) $PN AA82
J 2
(-4010 3985);
DISPLAY 0.617021 (-4010 3985);
PAINT ORANGE (-4010 3985);
FORCEPROP 2 LASTPIN (-4000 3925) $PN AB1
J 2
(-4010 3935);
DISPLAY 0.617021 (-4010 3935);
PAINT ORANGE (-4010 3935);
FORCEPROP 2 LASTPIN (-4000 3875) $PN AB5
J 2
(-4010 3885);
DISPLAY 0.617021 (-4010 3885);
PAINT ORANGE (-4010 3885);
FORCEPROP 2 LASTPIN (-4000 3825) $PN AB11
J 2
(-4010 3835);
DISPLAY 0.617021 (-4010 3835);
PAINT ORANGE (-4010 3835);
FORCEPROP 2 LASTPIN (-4000 3775) $PN AB21
J 2
(-4010 3785);
DISPLAY 0.617021 (-4010 3785);
PAINT ORANGE (-4010 3785);
FORCEPROP 2 LASTPIN (-4000 3725) $PN AB23
J 2
(-4010 3735);
DISPLAY 0.617021 (-4010 3735);
PAINT ORANGE (-4010 3735);
FORCEPROP 2 LASTPIN (-4000 3675) $PN AB25
J 2
(-4010 3685);
DISPLAY 0.617021 (-4010 3685);
PAINT ORANGE (-4010 3685);
FORCEPROP 2 LASTPIN (-4000 3625) $PN AB29
J 2
(-4010 3635);
DISPLAY 0.617021 (-4010 3635);
PAINT ORANGE (-4010 3635);
FORCEPROP 2 LASTPIN (-4000 3575) $PN AB31
J 2
(-4010 3585);
DISPLAY 0.617021 (-4010 3585);
PAINT ORANGE (-4010 3585);
FORCEPROP 2 LASTPIN (-4000 3525) $PN AB35
J 2
(-4010 3535);
DISPLAY 0.617021 (-4010 3535);
PAINT ORANGE (-4010 3535);
FORCEPROP 2 LASTPIN (-4000 3475) $PN AB37
J 2
(-4010 3485);
DISPLAY 0.617021 (-4010 3485);
PAINT ORANGE (-4010 3485);
FORCEPROP 2 LASTPIN (-4000 3425) $PN AB41
J 2
(-4010 3435);
DISPLAY 0.617021 (-4010 3435);
PAINT ORANGE (-4010 3435);
FORCEPROP 2 LASTPIN (-4000 3375) $PN AB65
J 2
(-4010 3385);
DISPLAY 0.617021 (-4010 3385);
PAINT ORANGE (-4010 3385);
FORCEPROP 2 LASTPIN (-4000 3325) $PN AB69
J 2
(-4010 3335);
DISPLAY 0.617021 (-4010 3335);
PAINT ORANGE (-4010 3335);
FORCEPROP 2 LASTPIN (-4000 3275) $PN AB73
J 2
(-4010 3285);
DISPLAY 0.617021 (-4010 3285);
PAINT ORANGE (-4010 3285);
FORCEPROP 2 LASTPIN (-4000 3225) $PN AB79
J 2
(-4010 3235);
DISPLAY 0.617021 (-4010 3235);
PAINT ORANGE (-4010 3235);
FORCEPROP 2 LASTPIN (-4000 3175) $PN AB83
J 2
(-4010 3185);
DISPLAY 0.617021 (-4010 3185);
PAINT ORANGE (-4010 3185);
FORCEPROP 2 LASTPIN (-4000 3125) $PN AB85
J 2
(-4010 3135);
DISPLAY 0.617021 (-4010 3135);
PAINT ORANGE (-4010 3135);
FORCEPROP 2 LASTPIN (-4000 3075) $PN AC18
J 2
(-4010 3085);
DISPLAY 0.617021 (-4010 3085);
PAINT ORANGE (-4010 3085);
FORCEPROP 2 LASTPIN (-4000 3025) $PN AC22
J 2
(-4010 3035);
DISPLAY 0.617021 (-4010 3035);
PAINT ORANGE (-4010 3035);
FORCEPROP 2 LASTPIN (-4000 2975) $PN AC26
J 2
(-4010 2985);
DISPLAY 0.617021 (-4010 2985);
PAINT ORANGE (-4010 2985);
FORCEPROP 2 LASTPIN (-4000 2925) $PN AC28
J 2
(-4010 2935);
DISPLAY 0.617021 (-4010 2935);
PAINT ORANGE (-4010 2935);
FORCEPROP 2 LASTPIN (-4000 2875) $PN AC32
J 2
(-4010 2885);
DISPLAY 0.617021 (-4010 2885);
PAINT ORANGE (-4010 2885);
FORCEPROP 2 LASTPIN (-4000 2825) $PN AC34
J 2
(-4010 2835);
DISPLAY 0.617021 (-4010 2835);
PAINT ORANGE (-4010 2835);
FORCEPROP 2 LASTPIN (-4000 2775) $PN AC38
J 2
(-4010 2785);
DISPLAY 0.617021 (-4010 2785);
PAINT ORANGE (-4010 2785);
FORCEPROP 2 LASTPIN (-4000 2725) $PN AC40
J 2
(-4010 2735);
DISPLAY 0.617021 (-4010 2735);
PAINT ORANGE (-4010 2735);
FORCEPROP 2 LASTPIN (-4000 2675) $PN AC64
J 2
(-4010 2685);
DISPLAY 0.617021 (-4010 2685);
PAINT ORANGE (-4010 2685);
FORCEPROP 2 LASTPIN (-4000 2625) $PN AC70
J 2
(-4010 2635);
DISPLAY 0.617021 (-4010 2635);
PAINT ORANGE (-4010 2635);
FORCEPROP 2 LASTPIN (-4000 2575) $PN AC72
J 2
(-4010 2585);
DISPLAY 0.617021 (-4010 2585);
PAINT ORANGE (-4010 2585);
FORCEPROP 2 LASTPIN (-4000 2525) $PN AC78
J 2
(-4010 2535);
DISPLAY 0.617021 (-4010 2535);
PAINT ORANGE (-4010 2535);
FORCEPROP 2 LASTPIN (-4000 2475) $PN AC84
J 2
(-4010 2485);
DISPLAY 0.617021 (-4010 2485);
PAINT ORANGE (-4010 2485);
FORCEPROP 2 LASTPIN (-4000 2425) $PN AC86
J 2
(-4010 2435);
DISPLAY 0.617021 (-4010 2435);
PAINT ORANGE (-4010 2435);
FORCEPROP 2 LASTPIN (-4000 2375) $PN AD3
J 2
(-4010 2385);
DISPLAY 0.617021 (-4010 2385);
PAINT ORANGE (-4010 2385);
FORCEPROP 2 LASTPIN (-4000 2325) $PN AD7
J 2
(-4010 2335);
DISPLAY 0.617021 (-4010 2335);
PAINT ORANGE (-4010 2335);
FORCEPROP 2 LASTPIN (-4000 2275) $PN AD9
J 2
(-4010 2285);
DISPLAY 0.617021 (-4010 2285);
PAINT ORANGE (-4010 2285);
FORCEPROP 2 LASTPIN (-4000 2225) $PN AD11
J 2
(-4010 2235);
DISPLAY 0.617021 (-4010 2235);
PAINT ORANGE (-4010 2235);
FORCEPROP 2 LASTPIN (-4000 2175) $PN AD13
J 2
(-4010 2185);
DISPLAY 0.617021 (-4010 2185);
PAINT ORANGE (-4010 2185);
FORCEPROP 2 LASTPIN (-4000 2125) $PN AD15
J 2
(-4010 2135);
DISPLAY 0.617021 (-4010 2135);
PAINT ORANGE (-4010 2135);
FORCEPROP 2 LASTPIN (-4000 2075) $PN AD19
J 2
(-4010 2085);
DISPLAY 0.617021 (-4010 2085);
PAINT ORANGE (-4010 2085);
FORCEPROP 2 LASTPIN (-4000 2025) $PN AD21
J 2
(-4010 2035);
DISPLAY 0.617021 (-4010 2035);
PAINT ORANGE (-4010 2035);
FORCEPROP 2 LASTPIN (-4000 1975) $PN AD27
J 2
(-4010 1985);
DISPLAY 0.617021 (-4010 1985);
PAINT ORANGE (-4010 1985);
FORCEPROP 2 LASTPIN (-4000 1925) $PN AD33
J 2
(-4010 1935);
DISPLAY 0.617021 (-4010 1935);
PAINT ORANGE (-4010 1935);
FORCEPROP 2 LASTPIN (-4000 1875) $PN AD39
J 2
(-4010 1885);
DISPLAY 0.617021 (-4010 1885);
PAINT ORANGE (-4010 1885);
FORCEPROP 2 LASTPIN (-4000 1825) $PN AD43
J 2
(-4010 1835);
DISPLAY 0.617021 (-4010 1835);
PAINT ORANGE (-4010 1835);
FORCEPROP 2 LASTPIN (-4000 1775) $PN AD71
J 2
(-4010 1785);
DISPLAY 0.617021 (-4010 1785);
PAINT ORANGE (-4010 1785);
FORCEPROP 2 LASTPIN (-4000 1725) $PN AD73
J 2
(-4010 1735);
DISPLAY 0.617021 (-4010 1735);
PAINT ORANGE (-4010 1735);
FORCEPROP 2 LASTPIN (-4000 1675) $PN AD75
J 2
(-4010 1685);
DISPLAY 0.617021 (-4010 1685);
PAINT ORANGE (-4010 1685);
FORCEPROP 2 LASTPIN (-4000 1625) $PN AD81
J 2
(-4010 1635);
DISPLAY 0.617021 (-4010 1635);
PAINT ORANGE (-4010 1635);
FORCEPROP 2 LASTPIN (-4000 1575) $PN AD83
J 2
(-4010 1585);
DISPLAY 0.617021 (-4010 1585);
PAINT ORANGE (-4010 1585);
FORCEPROP 2 LASTPIN (-4000 1525) $PN AD85
J 2
(-4010 1535);
DISPLAY 0.617021 (-4010 1535);
PAINT ORANGE (-4010 1535);
FORCEPROP 2 LASTPIN (-4000 1475) $PN AE4
J 2
(-4010 1485);
DISPLAY 0.617021 (-4010 1485);
PAINT ORANGE (-4010 1485);
FORCEPROP 2 LASTPIN (-4000 1425) $PN AE8
J 2
(-4010 1435);
DISPLAY 0.617021 (-4010 1435);
PAINT ORANGE (-4010 1435);
FORCEPROP 2 LASTPIN (-4000 1375) $PN AC54
J 2
(-4010 1385);
DISPLAY 0.617021 (-4010 1385);
PAINT ORANGE (-4010 1385);
FORCEPROP 2 LASTPIN (-4000 1325) $PN AE16
J 2
(-4010 1335);
DISPLAY 0.617021 (-4010 1335);
PAINT ORANGE (-4010 1335);
FORCEPROP 2 LASTPIN (-4000 1275) $PN AE38
J 2
(-4010 1285);
DISPLAY 0.617021 (-4010 1285);
PAINT ORANGE (-4010 1285);
FORCEPROP 2 LASTPIN (-4000 1225) $PN AE40
J 2
(-4010 1235);
DISPLAY 0.617021 (-4010 1235);
PAINT ORANGE (-4010 1235);
FORCEPROP 2 LASTPIN (-4000 1175) $PN AE42
J 2
(-4010 1185);
DISPLAY 0.617021 (-4010 1185);
PAINT ORANGE (-4010 1185);
FORCEPROP 2 LASTPIN (-4000 1125) $PN AE64
J 2
(-4010 1135);
DISPLAY 0.617021 (-4010 1135);
PAINT ORANGE (-4010 1135);
FORCEPROP 2 LASTPIN (-4000 1075) $PN AE66
J 2
(-4010 1085);
DISPLAY 0.617021 (-4010 1085);
PAINT ORANGE (-4010 1085);
FORCEPROP 2 LASTPIN (-4000 1025) $PN AE68
J 2
(-4010 1035);
DISPLAY 0.617021 (-4010 1035);
PAINT ORANGE (-4010 1035);
FORCEPROP 2 LASTPIN (-4000 975) $PN AE70
J 2
(-4010 985);
DISPLAY 0.617021 (-4010 985);
PAINT ORANGE (-4010 985);
FORCEPROP 2 LASTPIN (-4000 925) $PN AE78
J 2
(-4010 935);
DISPLAY 0.617021 (-4010 935);
PAINT ORANGE (-4010 935);
FORCEPROP 2 LASTPIN (-4000 875) $PN AF1
J 2
(-4010 885);
DISPLAY 0.617021 (-4010 885);
PAINT ORANGE (-4010 885);
FORCEPROP 2 LASTPIN (-4000 825) $PN AC52
J 2
(-4010 835);
DISPLAY 0.617021 (-4010 835);
PAINT ORANGE (-4010 835);
FORCEPROP 2 LASTPIN (-4000 775) $PN AF9
J 2
(-4010 785);
DISPLAY 0.617021 (-4010 785);
PAINT ORANGE (-4010 785);
FORCEPROP 2 LASTPIN (-4000 725) $PN AF21
J 2
(-4010 735);
DISPLAY 0.617021 (-4010 735);
PAINT ORANGE (-4010 735);
FORCEPROP 2 LASTPIN (-4000 675) $PN AF23
J 2
(-4010 685);
DISPLAY 0.617021 (-4010 685);
PAINT ORANGE (-4010 685);
FORCEPROP 2 LASTPIN (-4000 625) $PN AF25
J 2
(-4010 635);
DISPLAY 0.617021 (-4010 635);
PAINT ORANGE (-4010 635);
FORCEPROP 2 LASTPIN (-2800 4575) $PN AF27
J 0
(-2790 4585);
DISPLAY 0.617021 (-2790 4585);
PAINT ORANGE (-2790 4585);
FORCEPROP 2 LASTPIN (-2800 4525) $PN AF29
J 0
(-2790 4535);
DISPLAY 0.617021 (-2790 4535);
PAINT ORANGE (-2790 4535);
FORCEPROP 2 LASTPIN (-2800 4475) $PN AF31
J 0
(-2790 4485);
DISPLAY 0.617021 (-2790 4485);
PAINT ORANGE (-2790 4485);
FORCEPROP 2 LASTPIN (-2800 4425) $PN AF33
J 0
(-2790 4435);
DISPLAY 0.617021 (-2790 4435);
PAINT ORANGE (-2790 4435);
FORCEPROP 2 LASTPIN (-2800 4375) $PN AF37
J 0
(-2790 4385);
DISPLAY 0.617021 (-2790 4385);
PAINT ORANGE (-2790 4385);
FORCEPROP 2 LASTPIN (-2800 4325) $PN AF39
J 0
(-2790 4335);
DISPLAY 0.617021 (-2790 4335);
PAINT ORANGE (-2790 4335);
FORCEPROP 2 LASTPIN (-2800 4275) $PN AF41
J 0
(-2790 4285);
DISPLAY 0.617021 (-2790 4285);
PAINT ORANGE (-2790 4285);
FORCEPROP 2 LASTPIN (-2800 4225) $PN AF73
J 0
(-2790 4235);
DISPLAY 0.617021 (-2790 4235);
PAINT ORANGE (-2790 4235);
FORCEPROP 2 LASTPIN (-2800 4175) $PN AF77
J 0
(-2790 4185);
DISPLAY 0.617021 (-2790 4185);
PAINT ORANGE (-2790 4185);
FORCEPROP 2 LASTPIN (-2800 4125) $PN AF83
J 0
(-2790 4135);
DISPLAY 0.617021 (-2790 4135);
PAINT ORANGE (-2790 4135);
FORCEPROP 2 LASTPIN (-2800 4075) $PN AF85
J 0
(-2790 4085);
DISPLAY 0.617021 (-2790 4085);
PAINT ORANGE (-2790 4085);
FORCEPROP 2 LASTPIN (-2800 4025) $PN AG12
J 0
(-2790 4035);
DISPLAY 0.617021 (-2790 4035);
PAINT ORANGE (-2790 4035);
FORCEPROP 2 LASTPIN (-2800 3975) $PN AG14
J 0
(-2790 3985);
DISPLAY 0.617021 (-2790 3985);
PAINT ORANGE (-2790 3985);
FORCEPROP 2 LASTPIN (-2800 3925) $PN AG18
J 0
(-2790 3935);
DISPLAY 0.617021 (-2790 3935);
PAINT ORANGE (-2790 3935);
FORCEPROP 2 LASTPIN (-2800 3875) $PN AG36
J 0
(-2790 3885);
DISPLAY 0.617021 (-2790 3885);
PAINT ORANGE (-2790 3885);
FORCEPROP 2 LASTPIN (-2800 3825) $PN AG64
J 0
(-2790 3835);
DISPLAY 0.617021 (-2790 3835);
PAINT ORANGE (-2790 3835);
FORCEPROP 2 LASTPIN (-2800 3775) $PN AG70
J 0
(-2790 3785);
DISPLAY 0.617021 (-2790 3785);
PAINT ORANGE (-2790 3785);
FORCEPROP 2 LASTPIN (-2800 3725) $PN AG74
J 0
(-2790 3735);
DISPLAY 0.617021 (-2790 3735);
PAINT ORANGE (-2790 3735);
FORCEPROP 2 LASTPIN (-2800 3675) $PN AG76
J 0
(-2790 3685);
DISPLAY 0.617021 (-2790 3685);
PAINT ORANGE (-2790 3685);
FORCEPROP 2 LASTPIN (-2800 3625) $PN AG78
J 0
(-2790 3635);
DISPLAY 0.617021 (-2790 3635);
PAINT ORANGE (-2790 3635);
FORCEPROP 2 LASTPIN (-2800 3575) $PN AG80
J 0
(-2790 3585);
DISPLAY 0.617021 (-2790 3585);
PAINT ORANGE (-2790 3585);
FORCEPROP 2 LASTPIN (-2800 3525) $PN AH1
J 0
(-2790 3535);
DISPLAY 0.617021 (-2790 3535);
PAINT ORANGE (-2790 3535);
FORCEPROP 2 LASTPIN (-2800 3475) $PN AH5
J 0
(-2790 3485);
DISPLAY 0.617021 (-2790 3485);
PAINT ORANGE (-2790 3485);
FORCEPROP 2 LASTPIN (-2800 3425) $PN AH21
J 0
(-2790 3435);
DISPLAY 0.617021 (-2790 3435);
PAINT ORANGE (-2790 3435);
FORCEPROP 2 LASTPIN (-2800 3375) $PN AH27
J 0
(-2790 3385);
DISPLAY 0.617021 (-2790 3385);
PAINT ORANGE (-2790 3385);
FORCEPROP 2 LASTPIN (-2800 3325) $PN AH33
J 0
(-2790 3335);
DISPLAY 0.617021 (-2790 3335);
PAINT ORANGE (-2790 3335);
FORCEPROP 2 LASTPIN (-2800 3275) $PN AH35
J 0
(-2790 3285);
DISPLAY 0.617021 (-2790 3285);
PAINT ORANGE (-2790 3285);
FORCEPROP 2 LASTPIN (-2800 3225) $PN AH45
J 0
(-2790 3235);
DISPLAY 0.617021 (-2790 3235);
PAINT ORANGE (-2790 3235);
FORCEPROP 2 LASTPIN (-2800 3175) $PN AH47
J 0
(-2790 3185);
DISPLAY 0.617021 (-2790 3185);
PAINT ORANGE (-2790 3185);
FORCEPROP 2 LASTPIN (-2800 3125) $PN AH49
J 0
(-2790 3135);
DISPLAY 0.617021 (-2790 3135);
PAINT ORANGE (-2790 3135);
FORCEPROP 2 LASTPIN (-2800 3075) $PN AH51
J 0
(-2790 3085);
DISPLAY 0.617021 (-2790 3085);
PAINT ORANGE (-2790 3085);
FORCEPROP 2 LASTPIN (-2800 3025) $PN AH53
J 0
(-2790 3035);
DISPLAY 0.617021 (-2790 3035);
PAINT ORANGE (-2790 3035);
FORCEPROP 2 LASTPIN (-2800 2975) $PN AH59
J 0
(-2790 2985);
DISPLAY 0.617021 (-2790 2985);
PAINT ORANGE (-2790 2985);
FORCEPROP 2 LASTPIN (-2800 2925) $PN AH61
J 0
(-2790 2935);
DISPLAY 0.617021 (-2790 2935);
PAINT ORANGE (-2790 2935);
FORCEPROP 2 LASTPIN (-2800 2875) $PN AH65
J 0
(-2790 2885);
DISPLAY 0.617021 (-2790 2885);
PAINT ORANGE (-2790 2885);
FORCEPROP 2 LASTPIN (-2800 2825) $PN AH69
J 0
(-2790 2835);
DISPLAY 0.617021 (-2790 2835);
PAINT ORANGE (-2790 2835);
FORCEPROP 2 LASTPIN (-2800 2775) $PN AH75
J 0
(-2790 2785);
DISPLAY 0.617021 (-2790 2785);
PAINT ORANGE (-2790 2785);
FORCEPROP 2 LASTPIN (-2800 2725) $PN AH77
J 0
(-2790 2735);
DISPLAY 0.617021 (-2790 2735);
PAINT ORANGE (-2790 2735);
FORCEPROP 2 LASTPIN (-2800 2675) $PN AH83
J 0
(-2790 2685);
DISPLAY 0.617021 (-2790 2685);
PAINT ORANGE (-2790 2685);
FORCEPROP 2 LASTPIN (-2800 2625) $PN AJ8
J 0
(-2790 2635);
DISPLAY 0.617021 (-2790 2635);
PAINT ORANGE (-2790 2635);
FORCEPROP 2 LASTPIN (-2800 2575) $PN AJ22
J 0
(-2790 2585);
DISPLAY 0.617021 (-2790 2585);
PAINT ORANGE (-2790 2585);
FORCEPROP 2 LASTPIN (-2800 2525) $PN AJ26
J 0
(-2790 2535);
DISPLAY 0.617021 (-2790 2535);
PAINT ORANGE (-2790 2535);
FORCEPROP 2 LASTPIN (-2800 2475) $PN AJ28
J 0
(-2790 2485);
DISPLAY 0.617021 (-2790 2485);
PAINT ORANGE (-2790 2485);
FORCEPROP 2 LASTPIN (-2800 2425) $PN AJ32
J 0
(-2790 2435);
DISPLAY 0.617021 (-2790 2435);
PAINT ORANGE (-2790 2435);
FORCEPROP 2 LASTPIN (-2800 2375) $PN AJ34
J 0
(-2790 2385);
DISPLAY 0.617021 (-2790 2385);
PAINT ORANGE (-2790 2385);
FORCEPROP 2 LASTPIN (-2800 2325) $PN AJ46
J 0
(-2790 2335);
DISPLAY 0.617021 (-2790 2335);
PAINT ORANGE (-2790 2335);
FORCEPROP 2 LASTPIN (-2800 2275) $PN AJ48
J 0
(-2790 2285);
DISPLAY 0.617021 (-2790 2285);
PAINT ORANGE (-2790 2285);
FORCEPROP 2 LASTPIN (-2800 2225) $PN AJ50
J 0
(-2790 2235);
DISPLAY 0.617021 (-2790 2235);
PAINT ORANGE (-2790 2235);
FORCEPROP 2 LASTPIN (-2800 2175) $PN AJ52
J 0
(-2790 2185);
DISPLAY 0.617021 (-2790 2185);
PAINT ORANGE (-2790 2185);
FORCEPROP 2 LASTPIN (-2800 2125) $PN AJ54
J 0
(-2790 2135);
DISPLAY 0.617021 (-2790 2135);
PAINT ORANGE (-2790 2135);
FORCEPROP 2 LASTPIN (-2800 2075) $PN AJ66
J 0
(-2790 2085);
DISPLAY 0.617021 (-2790 2085);
PAINT ORANGE (-2790 2085);
FORCEPROP 2 LASTPIN (-2800 2025) $PN AJ68
J 0
(-2790 2035);
DISPLAY 0.617021 (-2790 2035);
PAINT ORANGE (-2790 2035);
FORCEPROP 2 LASTPIN (-2800 1975) $PN AJ74
J 0
(-2790 1985);
DISPLAY 0.617021 (-2790 1985);
PAINT ORANGE (-2790 1985);
FORCEPROP 2 LASTPIN (-2800 1925) $PN AJ78
J 0
(-2790 1935);
DISPLAY 0.617021 (-2790 1935);
PAINT ORANGE (-2790 1935);
FORCEPROP 2 LASTPIN (-2800 1875) $PN AJ82
J 0
(-2790 1885);
DISPLAY 0.617021 (-2790 1885);
PAINT ORANGE (-2790 1885);
FORCEPROP 2 LASTPIN (-2800 1825) $PN AJ86
J 0
(-2790 1835);
DISPLAY 0.617021 (-2790 1835);
PAINT ORANGE (-2790 1835);
FORCEPROP 2 LASTPIN (-2800 1775) $PN AK9
J 0
(-2790 1785);
DISPLAY 0.617021 (-2790 1785);
PAINT ORANGE (-2790 1785);
FORCEPROP 2 LASTPIN (-2800 1725) $PN AK13
J 0
(-2790 1735);
DISPLAY 0.617021 (-2790 1735);
PAINT ORANGE (-2790 1735);
FORCEPROP 2 LASTPIN (-2800 1675) $PN AK19
J 0
(-2790 1685);
DISPLAY 0.617021 (-2790 1685);
PAINT ORANGE (-2790 1685);
FORCEPROP 2 LASTPIN (-2800 1625) $PN AK23
J 0
(-2790 1635);
DISPLAY 0.617021 (-2790 1635);
PAINT ORANGE (-2790 1635);
FORCEPROP 2 LASTPIN (-2800 1575) $PN AK25
J 0
(-2790 1585);
DISPLAY 0.617021 (-2790 1585);
PAINT ORANGE (-2790 1585);
FORCEPROP 2 LASTPIN (-2800 1525) $PN AK29
J 0
(-2790 1535);
DISPLAY 0.617021 (-2790 1535);
PAINT ORANGE (-2790 1535);
FORCEPROP 2 LASTPIN (-2800 1475) $PN AK31
J 0
(-2790 1485);
DISPLAY 0.617021 (-2790 1485);
PAINT ORANGE (-2790 1485);
FORCEPROP 2 LASTPIN (-2800 1425) $PN AK33
J 0
(-2790 1435);
DISPLAY 0.617021 (-2790 1435);
PAINT ORANGE (-2790 1435);
FORCEPROP 2 LASTPIN (-2800 1375) $PN AK55
J 0
(-2790 1385);
DISPLAY 0.617021 (-2790 1385);
PAINT ORANGE (-2790 1385);
FORCEPROP 2 LASTPIN (-2800 1325) $PN AK65
J 0
(-2790 1335);
DISPLAY 0.617021 (-2790 1335);
PAINT ORANGE (-2790 1335);
FORCEPROP 2 LASTPIN (-2800 1275) $PN AK67
J 0
(-2790 1285);
DISPLAY 0.617021 (-2790 1285);
PAINT ORANGE (-2790 1285);
FORCEPROP 2 LASTPIN (-2800 1225) $PN AK73
J 0
(-2790 1235);
DISPLAY 0.617021 (-2790 1235);
PAINT ORANGE (-2790 1235);
FORCEPROP 2 LASTPIN (-2800 1175) $PN AK79
J 0
(-2790 1185);
DISPLAY 0.617021 (-2790 1185);
PAINT ORANGE (-2790 1185);
FORCEPROP 2 LASTPIN (-2800 1125) $PN AK81
J 0
(-2790 1135);
DISPLAY 0.617021 (-2790 1135);
PAINT ORANGE (-2790 1135);
FORCEPROP 2 LASTPIN (-2800 1075) $PN AK83
J 0
(-2790 1085);
DISPLAY 0.617021 (-2790 1085);
PAINT ORANGE (-2790 1085);
FORCEPROP 2 LASTPIN (-2800 1025) $PN AK85
J 0
(-2790 1035);
DISPLAY 0.617021 (-2790 1035);
PAINT ORANGE (-2790 1035);
FORCEPROP 2 LASTPIN (-2800 975) $PN AL4
J 0
(-2790 985);
DISPLAY 0.617021 (-2790 985);
PAINT ORANGE (-2790 985);
FORCEPROP 2 LASTPIN (-2800 925) $PN AL10
J 0
(-2790 935);
DISPLAY 0.617021 (-2790 935);
PAINT ORANGE (-2790 935);
FORCEPROP 2 LASTPIN (-2800 875) $PN AL24
J 0
(-2790 885);
DISPLAY 0.617021 (-2790 885);
PAINT ORANGE (-2790 885);
FORCEPROP 2 LASTPIN (-2800 825) $PN AL30
J 0
(-2790 835);
DISPLAY 0.617021 (-2790 835);
PAINT ORANGE (-2790 835);
FORCEPROP 2 LASTPIN (-2800 775) $PN AL32
J 0
(-2790 785);
DISPLAY 0.617021 (-2790 785);
PAINT ORANGE (-2790 785);
FORCEPROP 2 LASTPIN (-2800 725) $PN AL56
J 0
(-2790 735);
DISPLAY 0.617021 (-2790 735);
PAINT ORANGE (-2790 735);
FORCEPROP 2 LASTPIN (-2800 675) $PN AL64
J 0
(-2790 685);
DISPLAY 0.617021 (-2790 685);
PAINT ORANGE (-2790 685);
FORCEPROP 2 LASTPIN (-2800 625) $PN AL68
J 0
(-2790 635);
DISPLAY 0.617021 (-2790 635);
PAINT ORANGE (-2790 635);
FORCEPROP 1 LAST PACK_TYPE BGA1
J 0
(-3950 4875);
PAINT SKYBLUE (-3950 4875);
DISPLAY INVISIBLE (-3950 4875);
FORCEPROP 2 LAST SEC_TYPE BGA1
J 0
(-3950 4875);
DISPLAY 1.021277 (-3950 4875);
PAINT ORANGE (-3950 4875);
DISPLAY INVISIBLE (-3950 4875);
FORCEPROP 2 LAST CDS_LIB chpset_lib
J 0
(-3400 2575);
PAINT ORANGE (-3400 2575);
DISPLAY INVISIBLE (-3400 2575);
FORCEPROP 2 LAST SEC 25
J 0
(-3950 4875);
DISPLAY 0.680851 (-3950 4875);
PAINT MONO (-3950 4875);
DISPLAY INVISIBLE (-3950 4875);
FORCEPROP 2 LAST CDS_LOCATION U5D1
J 0
(-3950 4825);
DISPLAY 0.617021 (-3950 4825);
PAINT AQUA (-3950 4825);
DISPLAY INVISIBLE (-3950 4825);
FORCEPROP 1 LAST PATH I22
J 0
(-3400 4775);
PAINT GREEN (-3400 4775);
DISPLAY INVISIBLE (-3400 4775);
FORCEPROP 0 LAST ROOM CPU0
J 0
(-3950 4925);
DISPLAY 1.021277 (-3950 4925);
PAINT ORANGE (-3950 4925);
DISPLAY INVISIBLE (-3950 4925);
FORCEADD SKX_EXT_B..26
(-1550 2575);
FORCEPROP 1 LAST LOCATION U5D1
J 0
(-2100 4825);
DISPLAY 0.617021 (-2100 4825);
PAINT AQUA (-2100 4825);
FORCEPROP 1 LAST PART_NUMBER TBD
J 0
(-2100 425);
DISPLAY 0.617021 (-2100 425);
PAINT BLUE (-2100 425);
FORCEPROP 1 LAST MATERIAL IC
J 0
(-2100 4775);
DISPLAY 0.617021 (-2100 4775);
PAINT SKYBLUE (-2100 4775);
FORCEPROP 2 LASTPIN (-2150 4575) $PN AL76
J 2
(-2160 4585);
DISPLAY 0.617021 (-2160 4585);
PAINT ORANGE (-2160 4585);
FORCEPROP 2 LASTPIN (-2150 4525) $PN AL78
J 2
(-2160 4535);
DISPLAY 0.617021 (-2160 4535);
PAINT ORANGE (-2160 4535);
FORCEPROP 2 LASTPIN (-2150 4475) $PN AL80
J 2
(-2160 4485);
DISPLAY 0.617021 (-2160 4485);
PAINT ORANGE (-2160 4485);
FORCEPROP 2 LASTPIN (-2150 4425) $PN AL82
J 2
(-2160 4435);
DISPLAY 0.617021 (-2160 4435);
PAINT ORANGE (-2160 4435);
FORCEPROP 2 LASTPIN (-2150 4375) $PN AL86
J 2
(-2160 4385);
DISPLAY 0.617021 (-2160 4385);
PAINT ORANGE (-2160 4385);
FORCEPROP 2 LASTPIN (-2150 4325) $PN AM1
J 2
(-2160 4335);
DISPLAY 0.617021 (-2160 4335);
PAINT ORANGE (-2160 4335);
FORCEPROP 2 LASTPIN (-2150 4275) $PN AC50
J 2
(-2160 4285);
DISPLAY 0.617021 (-2160 4285);
PAINT ORANGE (-2160 4285);
FORCEPROP 2 LASTPIN (-2150 4225) $PN AM31
J 2
(-2160 4235);
DISPLAY 0.617021 (-2160 4235);
PAINT ORANGE (-2160 4235);
FORCEPROP 2 LASTPIN (-2150 4175) $PN AM57
J 2
(-2160 4185);
DISPLAY 0.617021 (-2160 4185);
PAINT ORANGE (-2160 4185);
FORCEPROP 2 LASTPIN (-2150 4125) $PN AM63
J 2
(-2160 4135);
DISPLAY 0.617021 (-2160 4135);
PAINT ORANGE (-2160 4135);
FORCEPROP 2 LASTPIN (-2150 4075) $PN AM69
J 2
(-2160 4085);
DISPLAY 0.617021 (-2160 4085);
PAINT ORANGE (-2160 4085);
FORCEPROP 2 LASTPIN (-2150 4025) $PN AM73
J 2
(-2160 4035);
DISPLAY 0.617021 (-2160 4035);
PAINT ORANGE (-2160 4035);
FORCEPROP 2 LASTPIN (-2150 3975) $PN AM79
J 2
(-2160 3985);
DISPLAY 0.617021 (-2160 3985);
PAINT ORANGE (-2160 3985);
FORCEPROP 2 LASTPIN (-2150 3925) $PN AM83
J 2
(-2160 3935);
DISPLAY 0.617021 (-2160 3935);
PAINT ORANGE (-2160 3935);
FORCEPROP 2 LASTPIN (-2150 3875) $PN AN2
J 2
(-2160 3885);
DISPLAY 0.617021 (-2160 3885);
PAINT ORANGE (-2160 3885);
FORCEPROP 2 LASTPIN (-2150 3825) $PN AN6
J 2
(-2160 3835);
DISPLAY 0.617021 (-2160 3835);
PAINT ORANGE (-2160 3835);
FORCEPROP 2 LASTPIN (-2150 3775) $PN AN28
J 2
(-2160 3785);
DISPLAY 0.617021 (-2160 3785);
PAINT ORANGE (-2160 3785);
FORCEPROP 2 LASTPIN (-2150 3725) $PN AN58
J 2
(-2160 3735);
DISPLAY 0.617021 (-2160 3735);
PAINT ORANGE (-2160 3735);
FORCEPROP 2 LASTPIN (-2150 3675) $PN AN78
J 2
(-2160 3685);
DISPLAY 0.617021 (-2160 3685);
PAINT ORANGE (-2160 3685);
FORCEPROP 2 LASTPIN (-2150 3625) $PN AP5
J 2
(-2160 3635);
DISPLAY 0.617021 (-2160 3635);
PAINT ORANGE (-2160 3635);
FORCEPROP 2 LASTPIN (-2150 3575) $PN AP9
J 2
(-2160 3585);
DISPLAY 0.617021 (-2160 3585);
PAINT ORANGE (-2160 3585);
FORCEPROP 2 LASTPIN (-2150 3525) $PN AP13
J 2
(-2160 3535);
DISPLAY 0.617021 (-2160 3535);
PAINT ORANGE (-2160 3535);
FORCEPROP 2 LASTPIN (-2150 3475) $PN AP19
J 2
(-2160 3485);
DISPLAY 0.617021 (-2160 3485);
PAINT ORANGE (-2160 3485);
FORCEPROP 2 LASTPIN (-2150 3425) $PN AP31
J 2
(-2160 3435);
DISPLAY 0.617021 (-2160 3435);
PAINT ORANGE (-2160 3435);
FORCEPROP 2 LASTPIN (-2150 3375) $PN AP59
J 2
(-2160 3385);
DISPLAY 0.617021 (-2160 3385);
PAINT ORANGE (-2160 3385);
FORCEPROP 2 LASTPIN (-2150 3325) $PN AP63
J 2
(-2160 3335);
DISPLAY 0.617021 (-2160 3335);
PAINT ORANGE (-2160 3335);
FORCEPROP 2 LASTPIN (-2150 3275) $PN AP65
J 2
(-2160 3285);
DISPLAY 0.617021 (-2160 3285);
PAINT ORANGE (-2160 3285);
FORCEPROP 2 LASTPIN (-2150 3225) $PN AP67
J 2
(-2160 3235);
DISPLAY 0.617021 (-2160 3235);
PAINT ORANGE (-2160 3235);
FORCEPROP 2 LASTPIN (-2150 3175) $PN AP69
J 2
(-2160 3185);
DISPLAY 0.617021 (-2160 3185);
PAINT ORANGE (-2160 3185);
FORCEPROP 2 LASTPIN (-2150 3125) $PN AP73
J 2
(-2160 3135);
DISPLAY 0.617021 (-2160 3135);
PAINT ORANGE (-2160 3135);
FORCEPROP 2 LASTPIN (-2150 3075) $PN AP75
J 2
(-2160 3085);
DISPLAY 0.617021 (-2160 3085);
PAINT ORANGE (-2160 3085);
FORCEPROP 2 LASTPIN (-2150 3025) $PN AP81
J 2
(-2160 3035);
DISPLAY 0.617021 (-2160 3035);
PAINT ORANGE (-2160 3035);
FORCEPROP 2 LASTPIN (-2150 2975) $PN AP83
J 2
(-2160 2985);
DISPLAY 0.617021 (-2160 2985);
PAINT ORANGE (-2160 2985);
FORCEPROP 2 LASTPIN (-2150 2925) $PN AP85
J 2
(-2160 2935);
DISPLAY 0.617021 (-2160 2935);
PAINT ORANGE (-2160 2935);
FORCEPROP 2 LASTPIN (-2150 2875) $PN AR10
J 2
(-2160 2885);
DISPLAY 0.617021 (-2160 2885);
PAINT ORANGE (-2160 2885);
FORCEPROP 2 LASTPIN (-2150 2825) $PN AR24
J 2
(-2160 2835);
DISPLAY 0.617021 (-2160 2835);
PAINT ORANGE (-2160 2835);
FORCEPROP 2 LASTPIN (-2150 2775) $PN AR30
J 2
(-2160 2785);
DISPLAY 0.617021 (-2160 2785);
PAINT ORANGE (-2160 2785);
FORCEPROP 2 LASTPIN (-2150 2725) $PN AR60
J 2
(-2160 2735);
DISPLAY 0.617021 (-2160 2735);
PAINT ORANGE (-2160 2735);
FORCEPROP 2 LASTPIN (-2150 2675) $PN AR72
J 2
(-2160 2685);
DISPLAY 0.617021 (-2160 2685);
PAINT ORANGE (-2160 2685);
FORCEPROP 2 LASTPIN (-2150 2625) $PN AR78
J 2
(-2160 2635);
DISPLAY 0.617021 (-2160 2635);
PAINT ORANGE (-2160 2635);
FORCEPROP 2 LASTPIN (-2150 2575) $PN AC48
J 2
(-2160 2585);
DISPLAY 0.617021 (-2160 2585);
PAINT ORANGE (-2160 2585);
FORCEPROP 2 LASTPIN (-2150 2525) $PN P63
J 2
(-2160 2535);
DISPLAY 0.617021 (-2160 2535);
PAINT ORANGE (-2160 2535);
FORCEPROP 2 LASTPIN (-2150 2475) $PN AT15
J 2
(-2160 2485);
DISPLAY 0.617021 (-2160 2485);
PAINT ORANGE (-2160 2485);
FORCEPROP 2 LASTPIN (-2150 2425) $PN AT17
J 2
(-2160 2435);
DISPLAY 0.617021 (-2160 2435);
PAINT ORANGE (-2160 2435);
FORCEPROP 2 LASTPIN (-2150 2375) $PN AT21
J 2
(-2160 2385);
DISPLAY 0.617021 (-2160 2385);
PAINT ORANGE (-2160 2385);
FORCEPROP 2 LASTPIN (-2150 2325) $PN AT27
J 2
(-2160 2335);
DISPLAY 0.617021 (-2160 2335);
PAINT ORANGE (-2160 2335);
FORCEPROP 2 LASTPIN (-2150 2275) $PN AT61
J 2
(-2160 2285);
DISPLAY 0.617021 (-2160 2285);
PAINT ORANGE (-2160 2285);
FORCEPROP 2 LASTPIN (-2150 2225) $PN AT63
J 2
(-2160 2235);
DISPLAY 0.617021 (-2160 2235);
PAINT ORANGE (-2160 2235);
FORCEPROP 2 LASTPIN (-2150 2175) $PN AT69
J 2
(-2160 2185);
DISPLAY 0.617021 (-2160 2185);
PAINT ORANGE (-2160 2185);
FORCEPROP 2 LASTPIN (-2150 2125) $PN AT73
J 2
(-2160 2135);
DISPLAY 0.617021 (-2160 2135);
PAINT ORANGE (-2160 2135);
FORCEPROP 2 LASTPIN (-2150 2075) $PN AT77
J 2
(-2160 2085);
DISPLAY 0.617021 (-2160 2085);
PAINT ORANGE (-2160 2085);
FORCEPROP 2 LASTPIN (-2150 2025) $PN AT83
J 2
(-2160 2035);
DISPLAY 0.617021 (-2160 2035);
PAINT ORANGE (-2160 2035);
FORCEPROP 2 LASTPIN (-2150 1975) $PN AT85
J 2
(-2160 1985);
DISPLAY 0.617021 (-2160 1985);
PAINT ORANGE (-2160 1985);
FORCEPROP 2 LASTPIN (-2150 1925) $PN AU2
J 2
(-2160 1935);
DISPLAY 0.617021 (-2160 1935);
PAINT ORANGE (-2160 1935);
FORCEPROP 2 LASTPIN (-2150 1875) $PN AU6
J 2
(-2160 1885);
DISPLAY 0.617021 (-2160 1885);
PAINT ORANGE (-2160 1885);
FORCEPROP 2 LASTPIN (-2150 1825) $PN AU26
J 2
(-2160 1835);
DISPLAY 0.617021 (-2160 1835);
PAINT ORANGE (-2160 1835);
FORCEPROP 2 LASTPIN (-2150 1775) $PN AU28
J 2
(-2160 1785);
DISPLAY 0.617021 (-2160 1785);
PAINT ORANGE (-2160 1785);
FORCEPROP 2 LASTPIN (-2150 1725) $PN AU62
J 2
(-2160 1735);
DISPLAY 0.617021 (-2160 1735);
PAINT ORANGE (-2160 1735);
FORCEPROP 2 LASTPIN (-2150 1675) $PN AU64
J 2
(-2160 1685);
DISPLAY 0.617021 (-2160 1685);
PAINT ORANGE (-2160 1685);
FORCEPROP 2 LASTPIN (-2150 1625) $PN AU68
J 2
(-2160 1635);
DISPLAY 0.617021 (-2160 1635);
PAINT ORANGE (-2160 1635);
FORCEPROP 2 LASTPIN (-2150 1575) $PN AU74
J 2
(-2160 1585);
DISPLAY 0.617021 (-2160 1585);
PAINT ORANGE (-2160 1585);
FORCEPROP 2 LASTPIN (-2150 1525) $PN AU76
J 2
(-2160 1535);
DISPLAY 0.617021 (-2160 1535);
PAINT ORANGE (-2160 1535);
FORCEPROP 2 LASTPIN (-2150 1475) $PN AU78
J 2
(-2160 1485);
DISPLAY 0.617021 (-2160 1485);
PAINT ORANGE (-2160 1485);
FORCEPROP 2 LASTPIN (-2150 1425) $PN AU80
J 2
(-2160 1435);
DISPLAY 0.617021 (-2160 1435);
PAINT ORANGE (-2160 1435);
FORCEPROP 2 LASTPIN (-2150 1375) $PN AU84
J 2
(-2160 1385);
DISPLAY 0.617021 (-2160 1385);
PAINT ORANGE (-2160 1385);
FORCEPROP 2 LASTPIN (-2150 1325) $PN AU86
J 2
(-2160 1335);
DISPLAY 0.617021 (-2160 1335);
PAINT ORANGE (-2160 1335);
FORCEPROP 2 LASTPIN (-2150 1275) $PN AV1
J 2
(-2160 1285);
DISPLAY 0.617021 (-2160 1285);
PAINT ORANGE (-2160 1285);
FORCEPROP 2 LASTPIN (-2150 1225) $PN AV3
J 2
(-2160 1235);
DISPLAY 0.617021 (-2160 1235);
PAINT ORANGE (-2160 1235);
FORCEPROP 2 LASTPIN (-2150 1175) $PN AV7
J 2
(-2160 1185);
DISPLAY 0.617021 (-2160 1185);
PAINT ORANGE (-2160 1185);
FORCEPROP 2 LASTPIN (-2150 1125) $PN AV11
J 2
(-2160 1135);
DISPLAY 0.617021 (-2160 1135);
PAINT ORANGE (-2160 1135);
FORCEPROP 2 LASTPIN (-2150 1075) $PN AV13
J 2
(-2160 1085);
DISPLAY 0.617021 (-2160 1085);
PAINT ORANGE (-2160 1085);
FORCEPROP 2 LASTPIN (-2150 1025) $PN AV19
J 2
(-2160 1035);
DISPLAY 0.617021 (-2160 1035);
PAINT ORANGE (-2160 1035);
FORCEPROP 2 LASTPIN (-2150 975) $PN AV23
J 2
(-2160 985);
DISPLAY 0.617021 (-2160 985);
PAINT ORANGE (-2160 985);
FORCEPROP 2 LASTPIN (-2150 925) $PN AV25
J 2
(-2160 935);
DISPLAY 0.617021 (-2160 935);
PAINT ORANGE (-2160 935);
FORCEPROP 2 LASTPIN (-2150 875) $PN AV63
J 2
(-2160 885);
DISPLAY 0.617021 (-2160 885);
PAINT ORANGE (-2160 885);
FORCEPROP 2 LASTPIN (-2150 825) $PN AV65
J 2
(-2160 835);
DISPLAY 0.617021 (-2160 835);
PAINT ORANGE (-2160 835);
FORCEPROP 2 LASTPIN (-2150 775) $PN AV67
J 2
(-2160 785);
DISPLAY 0.617021 (-2160 785);
PAINT ORANGE (-2160 785);
FORCEPROP 2 LASTPIN (-2150 725) $PN AV75
J 2
(-2160 735);
DISPLAY 0.617021 (-2160 735);
PAINT ORANGE (-2160 735);
FORCEPROP 2 LASTPIN (-2150 675) $PN AV83
J 2
(-2160 685);
DISPLAY 0.617021 (-2160 685);
PAINT ORANGE (-2160 685);
FORCEPROP 2 LASTPIN (-2150 625) $PN AW2
J 2
(-2160 635);
DISPLAY 0.617021 (-2160 635);
PAINT ORANGE (-2160 635);
FORCEPROP 2 LASTPIN (-950 4575) $PN AW10
J 0
(-940 4585);
DISPLAY 0.617021 (-940 4585);
PAINT ORANGE (-940 4585);
FORCEPROP 2 LASTPIN (-950 4525) $PN AW62
J 0
(-940 4535);
DISPLAY 0.617021 (-940 4535);
PAINT ORANGE (-940 4535);
FORCEPROP 2 LASTPIN (-950 4475) $PN AW66
J 0
(-940 4485);
DISPLAY 0.617021 (-940 4485);
PAINT ORANGE (-940 4485);
FORCEPROP 2 LASTPIN (-950 4425) $PN AW68
J 0
(-940 4435);
DISPLAY 0.617021 (-940 4435);
PAINT ORANGE (-940 4435);
FORCEPROP 2 LASTPIN (-950 4375) $PN AW70
J 0
(-940 4385);
DISPLAY 0.617021 (-940 4385);
PAINT ORANGE (-940 4385);
FORCEPROP 2 LASTPIN (-950 4325) $PN AW72
J 0
(-940 4335);
DISPLAY 0.617021 (-940 4335);
PAINT ORANGE (-940 4335);
FORCEPROP 2 LASTPIN (-950 4275) $PN AW74
J 0
(-940 4285);
DISPLAY 0.617021 (-940 4285);
PAINT ORANGE (-940 4285);
FORCEPROP 2 LASTPIN (-950 4225) $PN AW78
J 0
(-940 4235);
DISPLAY 0.617021 (-940 4235);
PAINT ORANGE (-940 4235);
FORCEPROP 2 LASTPIN (-950 4175) $PN AW82
J 0
(-940 4185);
DISPLAY 0.617021 (-940 4185);
PAINT ORANGE (-940 4185);
FORCEPROP 2 LASTPIN (-950 4125) $PN AW84
J 0
(-940 4135);
DISPLAY 0.617021 (-940 4135);
PAINT ORANGE (-940 4135);
FORCEPROP 2 LASTPIN (-950 4075) $PN AY5
J 0
(-940 4085);
DISPLAY 0.617021 (-940 4085);
PAINT ORANGE (-940 4085);
FORCEPROP 2 LASTPIN (-950 4025) $PN AY15
J 0
(-940 4035);
DISPLAY 0.617021 (-940 4035);
PAINT ORANGE (-940 4035);
FORCEPROP 2 LASTPIN (-950 3975) $PN AY17
J 0
(-940 3985);
DISPLAY 0.617021 (-940 3985);
PAINT ORANGE (-940 3985);
FORCEPROP 2 LASTPIN (-950 3925) $PN AY21
J 0
(-940 3935);
DISPLAY 0.617021 (-940 3935);
PAINT ORANGE (-940 3935);
FORCEPROP 2 LASTPIN (-950 3875) $PN AY23
J 0
(-940 3885);
DISPLAY 0.617021 (-940 3885);
PAINT ORANGE (-940 3885);
FORCEPROP 2 LASTPIN (-950 3825) $PN AY25
J 0
(-940 3835);
DISPLAY 0.617021 (-940 3835);
PAINT ORANGE (-940 3835);
FORCEPROP 2 LASTPIN (-950 3775) $PN AY63
J 0
(-940 3785);
DISPLAY 0.617021 (-940 3785);
PAINT ORANGE (-940 3785);
FORCEPROP 2 LASTPIN (-950 3725) $PN AY79
J 0
(-940 3735);
DISPLAY 0.617021 (-940 3735);
PAINT ORANGE (-940 3735);
FORCEPROP 2 LASTPIN (-950 3675) $PN AY81
J 0
(-940 3685);
DISPLAY 0.617021 (-940 3685);
PAINT ORANGE (-940 3685);
FORCEPROP 2 LASTPIN (-950 3625) $PN BA2
J 0
(-940 3635);
DISPLAY 0.617021 (-940 3635);
PAINT ORANGE (-940 3635);
FORCEPROP 2 LASTPIN (-950 3575) $PN BA6
J 0
(-940 3585);
DISPLAY 0.617021 (-940 3585);
PAINT ORANGE (-940 3585);
FORCEPROP 2 LASTPIN (-950 3525) $PN BA12
J 0
(-940 3535);
DISPLAY 0.617021 (-940 3535);
PAINT ORANGE (-940 3535);
FORCEPROP 2 LASTPIN (-950 3475) $PN BA62
J 0
(-940 3485);
DISPLAY 0.617021 (-940 3485);
PAINT ORANGE (-940 3485);
FORCEPROP 2 LASTPIN (-950 3425) $PN BA68
J 0
(-940 3435);
DISPLAY 0.617021 (-940 3435);
PAINT ORANGE (-940 3435);
FORCEPROP 2 LASTPIN (-950 3375) $PN BA74
J 0
(-940 3385);
DISPLAY 0.617021 (-940 3385);
PAINT ORANGE (-940 3385);
FORCEPROP 2 LASTPIN (-950 3325) $PN BA80
J 0
(-940 3335);
DISPLAY 0.617021 (-940 3335);
PAINT ORANGE (-940 3335);
FORCEPROP 2 LASTPIN (-950 3275) $PN BA84
J 0
(-940 3285);
DISPLAY 0.617021 (-940 3285);
PAINT ORANGE (-940 3285);
FORCEPROP 2 LASTPIN (-950 3225) $PN BB19
J 0
(-940 3235);
DISPLAY 0.617021 (-940 3235);
PAINT ORANGE (-940 3235);
FORCEPROP 2 LASTPIN (-950 3175) $PN BB23
J 0
(-940 3185);
DISPLAY 0.617021 (-940 3185);
PAINT ORANGE (-940 3185);
FORCEPROP 2 LASTPIN (-950 3125) $PN BB63
J 0
(-940 3135);
DISPLAY 0.617021 (-940 3135);
PAINT ORANGE (-940 3135);
FORCEPROP 2 LASTPIN (-950 3075) $PN BB69
J 0
(-940 3085);
DISPLAY 0.617021 (-940 3085);
PAINT ORANGE (-940 3085);
FORCEPROP 2 LASTPIN (-950 3025) $PN BB73
J 0
(-940 3035);
DISPLAY 0.617021 (-940 3035);
PAINT ORANGE (-940 3035);
FORCEPROP 2 LASTPIN (-950 2975) $PN BB75
J 0
(-940 2985);
DISPLAY 0.617021 (-940 2985);
PAINT ORANGE (-940 2985);
FORCEPROP 2 LASTPIN (-950 2925) $PN BB77
J 0
(-940 2935);
DISPLAY 0.617021 (-940 2935);
PAINT ORANGE (-940 2935);
FORCEPROP 2 LASTPIN (-950 2875) $PN BB79
J 0
(-940 2885);
DISPLAY 0.617021 (-940 2885);
PAINT ORANGE (-940 2885);
FORCEPROP 2 LASTPIN (-950 2825) $PN BB81
J 0
(-940 2835);
DISPLAY 0.617021 (-940 2835);
PAINT ORANGE (-940 2835);
FORCEPROP 2 LASTPIN (-950 2775) $PN BB83
J 0
(-940 2785);
DISPLAY 0.617021 (-940 2785);
PAINT ORANGE (-940 2785);
FORCEPROP 2 LASTPIN (-950 2725) $PN BC4
J 0
(-940 2735);
DISPLAY 0.617021 (-940 2735);
PAINT ORANGE (-940 2735);
FORCEPROP 2 LASTPIN (-950 2675) $PN BC8
J 0
(-940 2685);
DISPLAY 0.617021 (-940 2685);
PAINT ORANGE (-940 2685);
FORCEPROP 2 LASTPIN (-950 2625) $PN BC12
J 0
(-940 2635);
DISPLAY 0.617021 (-940 2635);
PAINT ORANGE (-940 2635);
FORCEPROP 2 LASTPIN (-950 2575) $PN BC16
J 0
(-940 2585);
DISPLAY 0.617021 (-940 2585);
PAINT ORANGE (-940 2585);
FORCEPROP 2 LASTPIN (-950 2525) $PN BC70
J 0
(-940 2535);
DISPLAY 0.617021 (-940 2535);
PAINT ORANGE (-940 2535);
FORCEPROP 2 LASTPIN (-950 2475) $PN BC72
J 0
(-940 2485);
DISPLAY 0.617021 (-940 2485);
PAINT ORANGE (-940 2485);
FORCEPROP 2 LASTPIN (-950 2425) $PN BC74
J 0
(-940 2435);
DISPLAY 0.617021 (-940 2435);
PAINT ORANGE (-940 2435);
FORCEPROP 2 LASTPIN (-950 2375) $PN BC76
J 0
(-940 2385);
DISPLAY 0.617021 (-940 2385);
PAINT ORANGE (-940 2385);
FORCEPROP 2 LASTPIN (-950 2325) $PN BC78
J 0
(-940 2335);
DISPLAY 0.617021 (-940 2335);
PAINT ORANGE (-940 2335);
FORCEPROP 2 LASTPIN (-950 2275) $PN BC80
J 0
(-940 2285);
DISPLAY 0.617021 (-940 2285);
PAINT ORANGE (-940 2285);
FORCEPROP 2 LASTPIN (-950 2225) $PN BC82
J 0
(-940 2235);
DISPLAY 0.617021 (-940 2235);
PAINT ORANGE (-940 2235);
FORCEPROP 2 LASTPIN (-950 2175) $PN BD5
J 0
(-940 2185);
DISPLAY 0.617021 (-940 2185);
PAINT ORANGE (-940 2185);
FORCEPROP 2 LASTPIN (-950 2125) $PN BD11
J 0
(-940 2135);
DISPLAY 0.617021 (-940 2135);
PAINT ORANGE (-940 2135);
FORCEPROP 2 LASTPIN (-950 2075) $PN BD15
J 0
(-940 2085);
DISPLAY 0.617021 (-940 2085);
PAINT ORANGE (-940 2085);
FORCEPROP 2 LASTPIN (-950 2025) $PN BD21
J 0
(-940 2035);
DISPLAY 0.617021 (-940 2035);
PAINT ORANGE (-940 2035);
FORCEPROP 2 LASTPIN (-950 1975) $PN BD27
J 0
(-940 1985);
DISPLAY 0.617021 (-940 1985);
PAINT ORANGE (-940 1985);
FORCEPROP 2 LASTPIN (-950 1925) $PN BD63
J 0
(-940 1935);
DISPLAY 0.617021 (-940 1935);
PAINT ORANGE (-940 1935);
FORCEPROP 2 LASTPIN (-950 1875) $PN BD71
J 0
(-940 1885);
DISPLAY 0.617021 (-940 1885);
PAINT ORANGE (-940 1885);
FORCEPROP 2 LASTPIN (-950 1825) $PN BE4
J 0
(-940 1835);
DISPLAY 0.617021 (-940 1835);
PAINT ORANGE (-940 1835);
FORCEPROP 2 LASTPIN (-950 1775) $PN BE6
J 0
(-940 1785);
DISPLAY 0.617021 (-940 1785);
PAINT ORANGE (-940 1785);
FORCEPROP 2 LASTPIN (-950 1725) $PN BE8
J 0
(-940 1735);
DISPLAY 0.617021 (-940 1735);
PAINT ORANGE (-940 1735);
FORCEPROP 2 LASTPIN (-950 1675) $PN BE10
J 0
(-940 1685);
DISPLAY 0.617021 (-940 1685);
PAINT ORANGE (-940 1685);
FORCEPROP 2 LASTPIN (-950 1625) $PN BE26
J 0
(-940 1635);
DISPLAY 0.617021 (-940 1635);
PAINT ORANGE (-940 1635);
FORCEPROP 2 LASTPIN (-950 1575) $PN BE64
J 0
(-940 1585);
DISPLAY 0.617021 (-940 1585);
PAINT ORANGE (-940 1585);
FORCEPROP 2 LASTPIN (-950 1525) $PN BE66
J 0
(-940 1535);
DISPLAY 0.617021 (-940 1535);
PAINT ORANGE (-940 1535);
FORCEPROP 2 LASTPIN (-950 1475) $PN BE68
J 0
(-940 1485);
DISPLAY 0.617021 (-940 1485);
PAINT ORANGE (-940 1485);
FORCEPROP 2 LASTPIN (-950 1425) $PN BE70
J 0
(-940 1435);
DISPLAY 0.617021 (-940 1435);
PAINT ORANGE (-940 1435);
FORCEPROP 2 LASTPIN (-950 1375) $PN BF9
J 0
(-940 1385);
DISPLAY 0.617021 (-940 1385);
PAINT ORANGE (-940 1385);
FORCEPROP 2 LASTPIN (-950 1325) $PN BF15
J 0
(-940 1335);
DISPLAY 0.617021 (-940 1335);
PAINT ORANGE (-940 1335);
FORCEPROP 2 LASTPIN (-950 1275) $PN BF17
J 0
(-940 1285);
DISPLAY 0.617021 (-940 1285);
PAINT ORANGE (-940 1285);
FORCEPROP 2 LASTPIN (-950 1225) $PN BF19
J 0
(-940 1235);
DISPLAY 0.617021 (-940 1235);
PAINT ORANGE (-940 1235);
FORCEPROP 2 LASTPIN (-950 1175) $PN BF25
J 0
(-940 1185);
DISPLAY 0.617021 (-940 1185);
PAINT ORANGE (-940 1185);
FORCEPROP 2 LASTPIN (-950 1125) $PN BF63
J 0
(-940 1135);
DISPLAY 0.617021 (-940 1135);
PAINT ORANGE (-940 1135);
FORCEPROP 2 LASTPIN (-950 1075) $PN BF65
J 0
(-940 1085);
DISPLAY 0.617021 (-940 1085);
PAINT ORANGE (-940 1085);
FORCEPROP 2 LASTPIN (-950 1025) $PN BF67
J 0
(-940 1035);
DISPLAY 0.617021 (-940 1035);
PAINT ORANGE (-940 1035);
FORCEPROP 2 LASTPIN (-950 975) $PN BF69
J 0
(-940 985);
DISPLAY 0.617021 (-940 985);
PAINT ORANGE (-940 985);
FORCEPROP 2 LASTPIN (-950 925) $PN BF71
J 0
(-940 935);
DISPLAY 0.617021 (-940 935);
PAINT ORANGE (-940 935);
FORCEPROP 2 LASTPIN (-950 875) $PN BG6
J 0
(-940 885);
DISPLAY 0.617021 (-940 885);
PAINT ORANGE (-940 885);
FORCEPROP 2 LASTPIN (-950 825) $PN BG8
J 0
(-940 835);
DISPLAY 0.617021 (-940 835);
PAINT ORANGE (-940 835);
FORCEPROP 2 LASTPIN (-950 775) $PN BG10
J 0
(-940 785);
DISPLAY 0.617021 (-940 785);
PAINT ORANGE (-940 785);
FORCEPROP 2 LASTPIN (-950 725) $PN BG22
J 0
(-940 735);
DISPLAY 0.617021 (-940 735);
PAINT ORANGE (-940 735);
FORCEPROP 2 LASTPIN (-950 675) $PN BG24
J 0
(-940 685);
DISPLAY 0.617021 (-940 685);
PAINT ORANGE (-940 685);
FORCEPROP 2 LASTPIN (-950 625) $PN BG72
J 0
(-940 635);
DISPLAY 0.617021 (-940 635);
PAINT ORANGE (-940 635);
FORCEPROP 1 LAST PACK_TYPE BGA1
J 0
(-2100 4875);
PAINT SKYBLUE (-2100 4875);
DISPLAY INVISIBLE (-2100 4875);
FORCEPROP 2 LAST SEC_TYPE BGA1
J 0
(-2100 4875);
DISPLAY 1.021277 (-2100 4875);
PAINT ORANGE (-2100 4875);
DISPLAY INVISIBLE (-2100 4875);
FORCEPROP 2 LAST CDS_LIB chpset_lib
J 0
(-1550 2575);
PAINT ORANGE (-1550 2575);
DISPLAY INVISIBLE (-1550 2575);
FORCEPROP 2 LAST SEC 26
J 0
(-2100 4875);
DISPLAY 0.680851 (-2100 4875);
PAINT MONO (-2100 4875);
DISPLAY INVISIBLE (-2100 4875);
FORCEPROP 2 LAST CDS_LOCATION U5D1
J 0
(-2100 4825);
DISPLAY 0.617021 (-2100 4825);
PAINT AQUA (-2100 4825);
DISPLAY INVISIBLE (-2100 4825);
FORCEPROP 1 LAST PATH I23
J 0
(-1550 4775);
PAINT GREEN (-1550 4775);
DISPLAY INVISIBLE (-1550 4775);
FORCEPROP 0 LAST ROOM CPU0
J 0
(-2100 4925);
DISPLAY 1.021277 (-2100 4925);
PAINT ORANGE (-2100 4925);
DISPLAY INVISIBLE (-2100 4925);
FORCEADD GND..1
(-7800 450);
FORCEPROP 3 LASTPIN (-7800 500) SIG_NAME GND\g
J 0
(-7790 510);
DISPLAY 0.659574 (-7790 510);
PAINT MONO (-7790 510);
DISPLAY INVISIBLE (-7790 510);
FORCEPROP 1 LAST VOLTAGE 0.0V
J 0
(-7845 407);
DISPLAY 0.340426 (-7845 407);
PAINT SKYBLUE (-7845 407);
DISPLAY INVISIBLE (-7845 407);
FORCEPROP 1 LAST SIZE 1B
J 0
(-7725 400);
DISPLAY 1.170213 (-7725 400);
PAINT AQUA (-7725 400);
DISPLAY INVISIBLE (-7725 400);
FORCEPROP 2 LAST CDS_LIB mstr_symbols
J 0
(-7800 450);
PAINT ORANGE (-7800 450);
DISPLAY INVISIBLE (-7800 450);
FORCEPROP 1 LAST BODY_TYPE PLUMBING
J 0
(-7845 407);
DISPLAY 0.340426 (-7845 407);
PAINT GREEN (-7845 407);
DISPLAY INVISIBLE (-7845 407);
FORCEPROP 1 LAST PATH I3
J 0
(-7725 450);
DISPLAY 1.170213 (-7725 450);
PAINT AQUA (-7725 450);
DISPLAY INVISIBLE (-7725 450);
FORCEPROP 1 LAST HDL_POWER GND
J 0
(-7800 600);
DISPLAY 1.170213 (-7800 600);
PAINT GREEN (-7800 600);
DISPLAY INVISIBLE (-7800 600);
FORCEADD GND..1
(-5975 450);
FORCEPROP 3 LASTPIN (-5975 500) SIG_NAME GND\g
J 0
(-5965 510);
DISPLAY 0.659574 (-5965 510);
PAINT MONO (-5965 510);
DISPLAY INVISIBLE (-5965 510);
FORCEPROP 1 LAST VOLTAGE 0.0V
J 0
(-6020 407);
DISPLAY 0.340426 (-6020 407);
PAINT SKYBLUE (-6020 407);
DISPLAY INVISIBLE (-6020 407);
FORCEPROP 1 LAST SIZE 1B
J 0
(-5900 400);
DISPLAY 1.170213 (-5900 400);
PAINT AQUA (-5900 400);
DISPLAY INVISIBLE (-5900 400);
FORCEPROP 2 LAST CDS_LIB mstr_symbols
J 0
(-5975 450);
PAINT ORANGE (-5975 450);
DISPLAY INVISIBLE (-5975 450);
FORCEPROP 1 LAST BODY_TYPE PLUMBING
J 0
(-6020 407);
DISPLAY 0.340426 (-6020 407);
PAINT GREEN (-6020 407);
DISPLAY INVISIBLE (-6020 407);
FORCEPROP 1 LAST PATH I4
J 0
(-5900 450);
DISPLAY 1.170213 (-5900 450);
PAINT AQUA (-5900 450);
DISPLAY INVISIBLE (-5900 450);
FORCEPROP 1 LAST HDL_POWER GND
J 0
(-5975 600);
DISPLAY 1.170213 (-5975 600);
PAINT GREEN (-5975 600);
DISPLAY INVISIBLE (-5975 600);
FORCEADD GND..1
(-6275 450);
FORCEPROP 3 LASTPIN (-6275 500) SIG_NAME GND\g
J 0
(-6265 510);
DISPLAY 0.659574 (-6265 510);
PAINT MONO (-6265 510);
DISPLAY INVISIBLE (-6265 510);
FORCEPROP 1 LAST VOLTAGE 0.0V
J 0
(-6320 407);
DISPLAY 0.340426 (-6320 407);
PAINT SKYBLUE (-6320 407);
DISPLAY INVISIBLE (-6320 407);
FORCEPROP 1 LAST SIZE 1B
J 0
(-6200 400);
DISPLAY 1.170213 (-6200 400);
PAINT AQUA (-6200 400);
DISPLAY INVISIBLE (-6200 400);
FORCEPROP 2 LAST CDS_LIB mstr_symbols
J 0
(-6275 450);
PAINT ORANGE (-6275 450);
DISPLAY INVISIBLE (-6275 450);
FORCEPROP 1 LAST BODY_TYPE PLUMBING
J 0
(-6320 407);
DISPLAY 0.340426 (-6320 407);
PAINT GREEN (-6320 407);
DISPLAY INVISIBLE (-6320 407);
FORCEPROP 1 LAST PATH I5
J 0
(-6200 450);
DISPLAY 1.170213 (-6200 450);
PAINT AQUA (-6200 450);
DISPLAY INVISIBLE (-6200 450);
FORCEPROP 1 LAST HDL_POWER GND
J 0
(-6275 600);
DISPLAY 1.170213 (-6275 600);
PAINT GREEN (-6275 600);
DISPLAY INVISIBLE (-6275 600);
FORCEADD GND..1
(-4450 450);
FORCEPROP 3 LASTPIN (-4450 500) SIG_NAME GND\g
J 0
(-4440 510);
DISPLAY 0.659574 (-4440 510);
PAINT MONO (-4440 510);
DISPLAY INVISIBLE (-4440 510);
FORCEPROP 1 LAST VOLTAGE 0.0V
J 0
(-4495 407);
DISPLAY 0.340426 (-4495 407);
PAINT SKYBLUE (-4495 407);
DISPLAY INVISIBLE (-4495 407);
FORCEPROP 1 LAST SIZE 1B
J 0
(-4375 400);
DISPLAY 1.170213 (-4375 400);
PAINT AQUA (-4375 400);
DISPLAY INVISIBLE (-4375 400);
FORCEPROP 2 LAST CDS_LIB mstr_symbols
J 0
(-4450 450);
PAINT ORANGE (-4450 450);
DISPLAY INVISIBLE (-4450 450);
FORCEPROP 1 LAST BODY_TYPE PLUMBING
J 0
(-4495 407);
DISPLAY 0.340426 (-4495 407);
PAINT GREEN (-4495 407);
DISPLAY INVISIBLE (-4495 407);
FORCEPROP 1 LAST PATH I6
J 0
(-4375 450);
DISPLAY 1.170213 (-4375 450);
PAINT AQUA (-4375 450);
DISPLAY INVISIBLE (-4375 450);
FORCEPROP 1 LAST HDL_POWER GND
J 0
(-4450 600);
DISPLAY 1.170213 (-4450 600);
PAINT GREEN (-4450 600);
DISPLAY INVISIBLE (-4450 600);
FORCEADD GND..1
(-4150 450);
FORCEPROP 3 LASTPIN (-4150 500) SIG_NAME GND\g
J 0
(-4140 510);
DISPLAY 0.659574 (-4140 510);
PAINT MONO (-4140 510);
DISPLAY INVISIBLE (-4140 510);
FORCEPROP 1 LAST VOLTAGE 0.0V
J 0
(-4195 407);
DISPLAY 0.340426 (-4195 407);
PAINT SKYBLUE (-4195 407);
DISPLAY INVISIBLE (-4195 407);
FORCEPROP 2 LAST CDS_LIB mstr_symbols
J 0
(-4150 450);
PAINT ORANGE (-4150 450);
DISPLAY INVISIBLE (-4150 450);
FORCEPROP 1 LAST SIZE 1B
J 0
(-4075 400);
DISPLAY 1.170213 (-4075 400);
PAINT AQUA (-4075 400);
DISPLAY INVISIBLE (-4075 400);
FORCEPROP 1 LAST BODY_TYPE PLUMBING
J 0
(-4195 407);
DISPLAY 0.340426 (-4195 407);
PAINT GREEN (-4195 407);
DISPLAY INVISIBLE (-4195 407);
FORCEPROP 1 LAST PATH I9
J 0
(-4075 450);
DISPLAY 0.872340 (-4075 450);
PAINT AQUA (-4075 450);
DISPLAY INVISIBLE (-4075 450);
FORCEPROP 1 LAST HDL_POWER GND
J 0
(-4150 600);
DISPLAY 1.170213 (-4150 600);
PAINT GREEN (-4150 600);
DISPLAY INVISIBLE (-4150 600);
FORCEADD DESIGN_NOTE..1
(-6625 225);
FORCEPROP 0 LAST L1 CPU SYMBOLS 1-30 ARE PRELIMINARY AND SUBJECT TO CHANGE
J 0
(-6825 100);
DISPLAY 1.021277 (-6825 100);
PAINT ORANGE (-6825 100);
FORCEPROP 2 LAST CDS_LIB mstr_symbols
J 0
(-6625 225);
PAINT ORANGE (-6625 225);
DISPLAY INVISIBLE (-6625 225);
FORCEPROP 1 LAST COMMENT_BODY TRUE
J 0
(-6600 325);
DISPLAY 0.978723 (-6600 325);
PAINT ORANGE (-6600 325);
DISPLAY INVISIBLE (-6600 325);
FORCEADD PRELIM..10
(-3390 2565);
PAINT GRAY (-3390 2565);
FORCEPROP 2 LAST CDS_LIB mstr_misc
J 0
(-3390 2565);
PAINT ORANGE (-3390 2565);
DISPLAY INVISIBLE (-3390 2565);
FORCEPROP 1 LAST COMMENT_BODY TRUE
J 0
(-3390 2565);
PAINT ORANGE (-3390 2565);
DISPLAY INVISIBLE (-3390 2565);
FORCEADD PRELIM..10
(-7040 2565);
PAINT GRAY (-7040 2565);
FORCEPROP 2 LAST CDS_LIB mstr_misc
J 0
(-7040 2565);
PAINT ORANGE (-7040 2565);
DISPLAY INVISIBLE (-7040 2565);
FORCEPROP 1 LAST COMMENT_BODY TRUE
J 0
(-7040 2565);
PAINT ORANGE (-7040 2565);
DISPLAY INVISIBLE (-7040 2565);
FORCEADD INTEL_CORP_BPAGE..1
(-300 25);
FORCEPROP 1 LAST CDS_CON_LAST_MODIFIED Tue Dec 01 11:51:24 2015
J 0
(-1725 350);
DISPLAY 1.340426 (-1725 350);
PAINT GREEN (-1725 350);
DISPLAY INVISIBLE (-1725 350);
FORCEPROP 1 LAST CUSTOM_TXT_CDS <CURRENT_DESIGN_SHEET> OF <TOTAL_DESIGN_SHEETS>
J 0
(-800 50);
PAINT GREEN (-800 50);
FORCEPROP 1 LAST CUSTOM_TXT_CDS <CON_LAST_MODIFIED>
J 0
(-2225 375);
PAINT GREEN (-2225 375);
FORCEPROP 2 LAST CUSTOM_TXT_CDS <XR_PAGE_TITLE>
J 0
(-8190 5275);
DISPLAY 0.638298 (-8190 5275);
PAINT PINK (-8190 5275);
DISPLAY INVISIBLE (-8190 5275);
FORCEPROP 1 LAST SCH_ADDRESS3 Santa Clara, CA 95052-8119
J 0
(-4275 50);
DISPLAY 0.617021 (-4275 50);
PAINT GREEN (-4275 50);
FORCEPROP 1 LAST SCH_ADDRESS2 P.O. BOX 58119
J 0
(-4275 100);
DISPLAY 0.617021 (-4275 100);
PAINT GREEN (-4275 100);
FORCEPROP 1 LAST SCH_ADDRESS1 2200 Mission College Blvd.
J 0
(-4275 150);
DISPLAY 0.617021 (-4275 150);
PAINT GREEN (-4275 150);
FORCEPROP 1 LAST SCH_TITLE SKYLAKE - SKT0 - 20 OF 21
J 0
(-8250 75);
DISPLAY 1.212766 (-8250 75);
PAINT GREEN (-8250 75);
FORCEPROP 1 LAST SCH_NUMBER H4694802
J 0
(-1600 175);
DISPLAY 1.212766 (-1600 175);
PAINT YELLOW (-1600 175);
FORCEPROP 1 LAST SCH_DEPT BESD
J 1
(-4750 125);
DISPLAY 1.212766 (-4750 125);
PAINT YELLOW (-4750 125);
FORCEPROP 1 LAST SCH_REV 2.420
J 0
(-550 175);
DISPLAY 0.978723 (-550 175);
PAINT YELLOW (-550 175);
FORCEPROP 2 LAST CDS_LIB mstr_symbols
J 0
(-300 25);
PAINT ORANGE (-300 25);
DISPLAY INVISIBLE (-300 25);
FORCEPROP 2 LAST PAGE_BORDER TRUE
J 0
(-8190 5275);
DISPLAY 0.851064 (-8190 5275);
PAINT PINK (-8190 5275);
DISPLAY INVISIBLE (-8190 5275);
FORCEPROP 1 LAST COMMENT_BODY TRUE
J 0
(-288 37);
DISPLAY 0.638298 (-288 37);
PAINT GREEN (-288 37);
DISPLAY INVISIBLE (-288 37);
FORCEPROP 2 LAST CDS_XR_PAGE_TITLE CR-40 : @BASEBOARD_FAB2_LIB.BASEBOARD_FAB2(SCH_1):PAGE40
J 0
(-8190 5275);
DISPLAY 0.638298 (-8190 5275);
PAINT PINK (-8190 5275);
DISPLAY INVISIBLE (-8190 5275);
FORCEADD PRELIM..10
(-5190 2565);
PAINT GRAY (-5190 2565);
FORCEPROP 2 LAST CDS_LIB mstr_misc
J 0
(-5190 2565);
PAINT ORANGE (-5190 2565);
DISPLAY INVISIBLE (-5190 2565);
FORCEPROP 1 LAST COMMENT_BODY TRUE
J 0
(-5190 2565);
PAINT ORANGE (-5190 2565);
DISPLAY INVISIBLE (-5190 2565);
FORCEADD PRELIM..10
(-1440 2565);
PAINT GRAY (-1440 2565);
FORCEPROP 2 LAST CDS_LIB mstr_misc
J 0
(-1440 2565);
PAINT ORANGE (-1440 2565);
DISPLAY INVISIBLE (-1440 2565);
FORCEPROP 1 LAST COMMENT_BODY TRUE
J 0
(-1440 2565);
PAINT ORANGE (-1440 2565);
DISPLAY INVISIBLE (-1440 2565);
WIRE 16 -1 (-2800 4575)(-2625 4575);
WIRE 16 -1 (-2625 4575)(-2625 4525);
WIRE 16 -1 (-2800 4525)(-2625 4525);
WIRE 16 -1 (-2625 4525)(-2625 4475);
WIRE 16 -1 (-2800 4475)(-2625 4475);
WIRE 16 -1 (-2625 4475)(-2625 4425);
WIRE 16 -1 (-2800 4425)(-2625 4425);
WIRE 16 -1 (-2625 4425)(-2625 4375);
WIRE 16 -1 (-2800 4375)(-2625 4375);
WIRE 16 -1 (-2625 4375)(-2625 4325);
WIRE 16 -1 (-2800 4325)(-2625 4325);
WIRE 16 -1 (-2625 4325)(-2625 4275);
WIRE 16 -1 (-2800 4275)(-2625 4275);
WIRE 16 -1 (-2625 4275)(-2625 4225);
WIRE 16 -1 (-2800 4225)(-2625 4225);
WIRE 16 -1 (-2625 4225)(-2625 4175);
WIRE 16 -1 (-2800 4175)(-2625 4175);
WIRE 16 -1 (-2625 4175)(-2625 4125);
WIRE 16 -1 (-2800 4125)(-2625 4125);
WIRE 16 -1 (-2625 4125)(-2625 4075);
WIRE 16 -1 (-2800 4075)(-2625 4075);
WIRE 16 -1 (-2625 4075)(-2625 4025);
WIRE 16 -1 (-2800 4025)(-2625 4025);
WIRE 16 -1 (-2625 4025)(-2625 3975);
WIRE 16 -1 (-2800 3975)(-2625 3975);
WIRE 16 -1 (-2625 3975)(-2625 3925);
WIRE 16 -1 (-2800 3925)(-2625 3925);
WIRE 16 -1 (-2625 3925)(-2625 3875);
WIRE 16 -1 (-2800 3875)(-2625 3875);
WIRE 16 -1 (-2625 3875)(-2625 3825);
WIRE 16 -1 (-2800 3825)(-2625 3825);
WIRE 16 -1 (-2625 3825)(-2625 3775);
WIRE 16 -1 (-2800 3775)(-2625 3775);
WIRE 16 -1 (-2625 3775)(-2625 3725);
WIRE 16 -1 (-2800 3725)(-2625 3725);
WIRE 16 -1 (-2625 3725)(-2625 3675);
WIRE 16 -1 (-2800 3675)(-2625 3675);
WIRE 16 -1 (-2625 3675)(-2625 3625);
WIRE 16 -1 (-2800 3625)(-2625 3625);
WIRE 16 -1 (-2625 3625)(-2625 3575);
WIRE 16 -1 (-2800 3575)(-2625 3575);
WIRE 16 -1 (-2625 3575)(-2625 3525);
WIRE 16 -1 (-2800 3525)(-2625 3525);
WIRE 16 -1 (-2625 3525)(-2625 3475);
WIRE 16 -1 (-2800 3475)(-2625 3475);
WIRE 16 -1 (-2625 3475)(-2625 3425);
WIRE 16 -1 (-2800 3425)(-2625 3425);
WIRE 16 -1 (-2625 3425)(-2625 3375);
WIRE 16 -1 (-2800 3375)(-2625 3375);
WIRE 16 -1 (-2625 3375)(-2625 3325);
WIRE 16 -1 (-2800 3325)(-2625 3325);
WIRE 16 -1 (-2625 3325)(-2625 3275);
WIRE 16 -1 (-2800 3275)(-2625 3275);
WIRE 16 -1 (-2625 3275)(-2625 3225);
WIRE 16 -1 (-2800 3225)(-2625 3225);
WIRE 16 -1 (-2625 3225)(-2625 3175);
WIRE 16 -1 (-2800 3175)(-2625 3175);
WIRE 16 -1 (-2625 3175)(-2625 3125);
WIRE 16 -1 (-2800 3125)(-2625 3125);
WIRE 16 -1 (-2625 3125)(-2625 3075);
WIRE 16 -1 (-2800 3075)(-2625 3075);
WIRE 16 -1 (-2625 3075)(-2625 3025);
WIRE 16 -1 (-2800 3025)(-2625 3025);
WIRE 16 -1 (-2625 3025)(-2625 2975);
WIRE 16 -1 (-2800 2975)(-2625 2975);
WIRE 16 -1 (-2625 2975)(-2625 2925);
WIRE 16 -1 (-2800 2925)(-2625 2925);
WIRE 16 -1 (-2625 2925)(-2625 2875);
WIRE 16 -1 (-2800 2875)(-2625 2875);
WIRE 16 -1 (-2625 2875)(-2625 2825);
WIRE 16 -1 (-2800 2825)(-2625 2825);
WIRE 16 -1 (-2625 2825)(-2625 2775);
WIRE 16 -1 (-2800 2775)(-2625 2775);
WIRE 16 -1 (-2625 2775)(-2625 2725);
WIRE 16 -1 (-2800 2725)(-2625 2725);
WIRE 16 -1 (-2625 2725)(-2625 2675);
WIRE 16 -1 (-2800 2675)(-2625 2675);
WIRE 16 -1 (-2625 2675)(-2625 2625);
WIRE 16 -1 (-2800 2625)(-2625 2625);
WIRE 16 -1 (-2625 2625)(-2625 2575);
WIRE 16 -1 (-2800 2575)(-2625 2575);
WIRE 16 -1 (-2625 2575)(-2625 2525);
WIRE 16 -1 (-2800 2525)(-2625 2525);
WIRE 16 -1 (-2625 2525)(-2625 2475);
WIRE 16 -1 (-2800 2475)(-2625 2475);
WIRE 16 -1 (-2625 2475)(-2625 2425);
WIRE 16 -1 (-2800 2425)(-2625 2425);
WIRE 16 -1 (-2625 2425)(-2625 2375);
WIRE 16 -1 (-2800 2375)(-2625 2375);
WIRE 16 -1 (-2625 2375)(-2625 2325);
WIRE 16 -1 (-2800 2325)(-2625 2325);
WIRE 16 -1 (-2625 2325)(-2625 2275);
WIRE 16 -1 (-2800 2275)(-2625 2275);
WIRE 16 -1 (-2625 2275)(-2625 2225);
WIRE 16 -1 (-2800 2225)(-2625 2225);
WIRE 16 -1 (-2625 2225)(-2625 2175);
WIRE 16 -1 (-2800 2175)(-2625 2175);
WIRE 16 -1 (-2625 2175)(-2625 2125);
WIRE 16 -1 (-2800 2125)(-2625 2125);
WIRE 16 -1 (-2625 2125)(-2625 2075);
WIRE 16 -1 (-2800 2075)(-2625 2075);
WIRE 16 -1 (-2625 2075)(-2625 2025);
WIRE 16 -1 (-2800 2025)(-2625 2025);
WIRE 16 -1 (-2625 2025)(-2625 1975);
WIRE 16 -1 (-2800 1975)(-2625 1975);
WIRE 16 -1 (-2625 1975)(-2625 1925);
WIRE 16 -1 (-2800 1925)(-2625 1925);
WIRE 16 -1 (-2625 1925)(-2625 1875);
WIRE 16 -1 (-2800 1875)(-2625 1875);
WIRE 16 -1 (-2625 1875)(-2625 1825);
WIRE 16 -1 (-2800 1825)(-2625 1825);
WIRE 16 -1 (-2625 1825)(-2625 1775);
WIRE 16 -1 (-2800 1775)(-2625 1775);
WIRE 16 -1 (-2625 1775)(-2625 1725);
WIRE 16 -1 (-2800 1725)(-2625 1725);
WIRE 16 -1 (-2625 1725)(-2625 1675);
WIRE 16 -1 (-2800 1675)(-2625 1675);
WIRE 16 -1 (-2625 1675)(-2625 1625);
WIRE 16 -1 (-2800 1625)(-2625 1625);
WIRE 16 -1 (-2625 1625)(-2625 1575);
WIRE 16 -1 (-2800 1575)(-2625 1575);
WIRE 16 -1 (-2625 1575)(-2625 1525);
WIRE 16 -1 (-2800 1525)(-2625 1525);
WIRE 16 -1 (-2625 1525)(-2625 1475);
WIRE 16 -1 (-2800 1475)(-2625 1475);
WIRE 16 -1 (-2625 1475)(-2625 1425);
WIRE 16 -1 (-2800 1425)(-2625 1425);
WIRE 16 -1 (-2625 1425)(-2625 1375);
WIRE 16 -1 (-2800 1375)(-2625 1375);
WIRE 16 -1 (-2625 1375)(-2625 1325);
WIRE 16 -1 (-2800 1325)(-2625 1325);
WIRE 16 -1 (-2625 1325)(-2625 1275);
WIRE 16 -1 (-2800 1275)(-2625 1275);
WIRE 16 -1 (-2625 1275)(-2625 1225);
WIRE 16 -1 (-2800 1225)(-2625 1225);
WIRE 16 -1 (-2625 1225)(-2625 1175);
WIRE 16 -1 (-2800 1175)(-2625 1175);
WIRE 16 -1 (-2625 1175)(-2625 1125);
WIRE 16 -1 (-2800 1125)(-2625 1125);
WIRE 16 -1 (-2625 1125)(-2625 1075);
WIRE 16 -1 (-2800 1075)(-2625 1075);
WIRE 16 -1 (-2625 1075)(-2625 1025);
WIRE 16 -1 (-2800 1025)(-2625 1025);
WIRE 16 -1 (-2625 1025)(-2625 975);
WIRE 16 -1 (-2800 975)(-2625 975);
WIRE 16 -1 (-2625 975)(-2625 925);
WIRE 16 -1 (-2800 925)(-2625 925);
WIRE 16 -1 (-2625 925)(-2625 875);
WIRE 16 -1 (-2800 875)(-2625 875);
WIRE 16 -1 (-2625 875)(-2625 825);
WIRE 16 -1 (-2800 825)(-2625 825);
WIRE 16 -1 (-2625 825)(-2625 775);
WIRE 16 -1 (-2800 775)(-2625 775);
WIRE 16 -1 (-2625 775)(-2625 725);
WIRE 16 -1 (-2800 725)(-2625 725);
WIRE 16 -1 (-2625 725)(-2625 675);
WIRE 16 -1 (-2800 675)(-2625 675);
WIRE 16 -1 (-2625 675)(-2625 625);
WIRE 16 -1 (-2800 625)(-2625 625);
WIRE 16 -1 (-2625 625)(-2625 500);
WIRE 16 -1 (-950 4575)(-775 4575);
WIRE 16 -1 (-775 4575)(-775 4525);
WIRE 16 -1 (-950 4525)(-775 4525);
WIRE 16 -1 (-775 4525)(-775 4475);
WIRE 16 -1 (-950 4475)(-775 4475);
WIRE 16 -1 (-775 4475)(-775 4425);
WIRE 16 -1 (-950 4425)(-775 4425);
WIRE 16 -1 (-775 4425)(-775 4375);
WIRE 16 -1 (-950 4375)(-775 4375);
WIRE 16 -1 (-775 4375)(-775 4325);
WIRE 16 -1 (-950 4325)(-775 4325);
WIRE 16 -1 (-775 4325)(-775 4275);
WIRE 16 -1 (-950 4275)(-775 4275);
WIRE 16 -1 (-775 4275)(-775 4225);
WIRE 16 -1 (-950 4225)(-775 4225);
WIRE 16 -1 (-775 4225)(-775 4175);
WIRE 16 -1 (-950 4175)(-775 4175);
WIRE 16 -1 (-775 4175)(-775 4125);
WIRE 16 -1 (-950 4125)(-775 4125);
WIRE 16 -1 (-775 4125)(-775 4075);
WIRE 16 -1 (-950 4075)(-775 4075);
WIRE 16 -1 (-775 4075)(-775 4025);
WIRE 16 -1 (-950 4025)(-775 4025);
WIRE 16 -1 (-775 4025)(-775 3975);
WIRE 16 -1 (-950 3975)(-775 3975);
WIRE 16 -1 (-775 3975)(-775 3925);
WIRE 16 -1 (-950 3925)(-775 3925);
WIRE 16 -1 (-775 3925)(-775 3875);
WIRE 16 -1 (-950 3875)(-775 3875);
WIRE 16 -1 (-775 3875)(-775 3825);
WIRE 16 -1 (-950 3825)(-775 3825);
WIRE 16 -1 (-775 3825)(-775 3775);
WIRE 16 -1 (-950 3775)(-775 3775);
WIRE 16 -1 (-775 3775)(-775 3725);
WIRE 16 -1 (-950 3725)(-775 3725);
WIRE 16 -1 (-775 3725)(-775 3675);
WIRE 16 -1 (-950 3675)(-775 3675);
WIRE 16 -1 (-775 3675)(-775 3625);
WIRE 16 -1 (-950 3625)(-775 3625);
WIRE 16 -1 (-775 3625)(-775 3575);
WIRE 16 -1 (-950 3575)(-775 3575);
WIRE 16 -1 (-775 3575)(-775 3525);
WIRE 16 -1 (-950 3525)(-775 3525);
WIRE 16 -1 (-775 3525)(-775 3475);
WIRE 16 -1 (-950 3475)(-775 3475);
WIRE 16 -1 (-775 3475)(-775 3425);
WIRE 16 -1 (-950 3425)(-775 3425);
WIRE 16 -1 (-775 3425)(-775 3375);
WIRE 16 -1 (-950 3375)(-775 3375);
WIRE 16 -1 (-775 3375)(-775 3325);
WIRE 16 -1 (-950 3325)(-775 3325);
WIRE 16 -1 (-775 3325)(-775 3275);
WIRE 16 -1 (-950 3275)(-775 3275);
WIRE 16 -1 (-775 3275)(-775 3225);
WIRE 16 -1 (-950 3225)(-775 3225);
WIRE 16 -1 (-775 3225)(-775 3175);
WIRE 16 -1 (-950 3175)(-775 3175);
WIRE 16 -1 (-775 3175)(-775 3125);
WIRE 16 -1 (-950 3125)(-775 3125);
WIRE 16 -1 (-775 3125)(-775 3075);
WIRE 16 -1 (-950 3075)(-775 3075);
WIRE 16 -1 (-775 3075)(-775 3025);
WIRE 16 -1 (-950 3025)(-775 3025);
WIRE 16 -1 (-775 3025)(-775 2975);
WIRE 16 -1 (-950 2975)(-775 2975);
WIRE 16 -1 (-775 2975)(-775 2925);
WIRE 16 -1 (-950 2925)(-775 2925);
WIRE 16 -1 (-775 2925)(-775 2875);
WIRE 16 -1 (-950 2875)(-775 2875);
WIRE 16 -1 (-775 2875)(-775 2825);
WIRE 16 -1 (-950 2825)(-775 2825);
WIRE 16 -1 (-775 2825)(-775 2775);
WIRE 16 -1 (-950 2775)(-775 2775);
WIRE 16 -1 (-775 2775)(-775 2725);
WIRE 16 -1 (-950 2725)(-775 2725);
WIRE 16 -1 (-775 2725)(-775 2675);
WIRE 16 -1 (-950 2675)(-775 2675);
WIRE 16 -1 (-775 2675)(-775 2625);
WIRE 16 -1 (-950 2625)(-775 2625);
WIRE 16 -1 (-775 2625)(-775 2575);
WIRE 16 -1 (-950 2575)(-775 2575);
WIRE 16 -1 (-775 2575)(-775 2525);
WIRE 16 -1 (-950 2525)(-775 2525);
WIRE 16 -1 (-775 2525)(-775 2475);
WIRE 16 -1 (-950 2475)(-775 2475);
WIRE 16 -1 (-775 2475)(-775 2425);
WIRE 16 -1 (-950 2425)(-775 2425);
WIRE 16 -1 (-775 2425)(-775 2375);
WIRE 16 -1 (-950 2375)(-775 2375);
WIRE 16 -1 (-775 2375)(-775 2325);
WIRE 16 -1 (-950 2325)(-775 2325);
WIRE 16 -1 (-775 2325)(-775 2275);
WIRE 16 -1 (-950 2275)(-775 2275);
WIRE 16 -1 (-775 2275)(-775 2225);
WIRE 16 -1 (-950 2225)(-775 2225);
WIRE 16 -1 (-775 2225)(-775 2175);
WIRE 16 -1 (-950 2175)(-775 2175);
WIRE 16 -1 (-775 2175)(-775 2125);
WIRE 16 -1 (-950 2125)(-775 2125);
WIRE 16 -1 (-775 2125)(-775 2075);
WIRE 16 -1 (-950 2075)(-775 2075);
WIRE 16 -1 (-775 2075)(-775 2025);
WIRE 16 -1 (-950 2025)(-775 2025);
WIRE 16 -1 (-775 2025)(-775 1975);
WIRE 16 -1 (-950 1975)(-775 1975);
WIRE 16 -1 (-775 1975)(-775 1925);
WIRE 16 -1 (-950 1925)(-775 1925);
WIRE 16 -1 (-775 1925)(-775 1875);
WIRE 16 -1 (-950 1875)(-775 1875);
WIRE 16 -1 (-775 1875)(-775 1825);
WIRE 16 -1 (-950 1825)(-775 1825);
WIRE 16 -1 (-775 1825)(-775 1775);
WIRE 16 -1 (-950 1775)(-775 1775);
WIRE 16 -1 (-775 1775)(-775 1725);
WIRE 16 -1 (-950 1725)(-775 1725);
WIRE 16 -1 (-775 1725)(-775 1675);
WIRE 16 -1 (-950 1675)(-775 1675);
WIRE 16 -1 (-775 1675)(-775 1625);
WIRE 16 -1 (-950 1625)(-775 1625);
WIRE 16 -1 (-775 1625)(-775 1575);
WIRE 16 -1 (-950 1575)(-775 1575);
WIRE 16 -1 (-775 1575)(-775 1525);
WIRE 16 -1 (-950 1525)(-775 1525);
WIRE 16 -1 (-775 1525)(-775 1475);
WIRE 16 -1 (-950 1475)(-775 1475);
WIRE 16 -1 (-775 1475)(-775 1425);
WIRE 16 -1 (-950 1425)(-775 1425);
WIRE 16 -1 (-775 1425)(-775 1375);
WIRE 16 -1 (-950 1375)(-775 1375);
WIRE 16 -1 (-775 1375)(-775 1325);
WIRE 16 -1 (-950 1325)(-775 1325);
WIRE 16 -1 (-775 1325)(-775 1275);
WIRE 16 -1 (-950 1275)(-775 1275);
WIRE 16 -1 (-775 1275)(-775 1225);
WIRE 16 -1 (-950 1225)(-775 1225);
WIRE 16 -1 (-775 1225)(-775 1175);
WIRE 16 -1 (-950 1175)(-775 1175);
WIRE 16 -1 (-775 1175)(-775 1125);
WIRE 16 -1 (-950 1125)(-775 1125);
WIRE 16 -1 (-775 1125)(-775 1075);
WIRE 16 -1 (-950 1075)(-775 1075);
WIRE 16 -1 (-775 1075)(-775 1025);
WIRE 16 -1 (-950 1025)(-775 1025);
WIRE 16 -1 (-775 1025)(-775 975);
WIRE 16 -1 (-950 975)(-775 975);
WIRE 16 -1 (-775 975)(-775 925);
WIRE 16 -1 (-950 925)(-775 925);
WIRE 16 -1 (-775 925)(-775 875);
WIRE 16 -1 (-950 875)(-775 875);
WIRE 16 -1 (-775 875)(-775 825);
WIRE 16 -1 (-950 825)(-775 825);
WIRE 16 -1 (-775 825)(-775 775);
WIRE 16 -1 (-950 775)(-775 775);
WIRE 16 -1 (-775 775)(-775 725);
WIRE 16 -1 (-950 725)(-775 725);
WIRE 16 -1 (-775 725)(-775 675);
WIRE 16 -1 (-950 675)(-775 675);
WIRE 16 -1 (-775 675)(-775 625);
WIRE 16 -1 (-950 625)(-775 625);
WIRE 16 -1 (-775 625)(-775 500);
WIRE 16 -1 (-2150 4575)(-2325 4575);
WIRE 16 -1 (-2325 4575)(-2325 4525);
WIRE 16 -1 (-2150 4525)(-2325 4525);
WIRE 16 -1 (-2325 4525)(-2325 4475);
WIRE 16 -1 (-2150 4475)(-2325 4475);
WIRE 16 -1 (-2325 4475)(-2325 4425);
WIRE 16 -1 (-2150 4425)(-2325 4425);
WIRE 16 -1 (-2325 4425)(-2325 4375);
WIRE 16 -1 (-2150 4375)(-2325 4375);
WIRE 16 -1 (-2325 4375)(-2325 4325);
WIRE 16 -1 (-2150 4325)(-2325 4325);
WIRE 16 -1 (-2325 4325)(-2325 4275);
WIRE 16 -1 (-2150 4275)(-2325 4275);
WIRE 16 -1 (-2325 4275)(-2325 4225);
WIRE 16 -1 (-2150 4225)(-2325 4225);
WIRE 16 -1 (-2325 4225)(-2325 4175);
WIRE 16 -1 (-2150 4175)(-2325 4175);
WIRE 16 -1 (-2325 4175)(-2325 4125);
WIRE 16 -1 (-2150 4125)(-2325 4125);
WIRE 16 -1 (-2325 4125)(-2325 4075);
WIRE 16 -1 (-2150 4075)(-2325 4075);
WIRE 16 -1 (-2325 4075)(-2325 4025);
WIRE 16 -1 (-2150 4025)(-2325 4025);
WIRE 16 -1 (-2325 4025)(-2325 3975);
WIRE 16 -1 (-2150 3975)(-2325 3975);
WIRE 16 -1 (-2325 3975)(-2325 3925);
WIRE 16 -1 (-2150 3925)(-2325 3925);
WIRE 16 -1 (-2325 3925)(-2325 3875);
WIRE 16 -1 (-2150 3875)(-2325 3875);
WIRE 16 -1 (-2325 3875)(-2325 3825);
WIRE 16 -1 (-2150 3825)(-2325 3825);
WIRE 16 -1 (-2325 3825)(-2325 3775);
WIRE 16 -1 (-2150 3775)(-2325 3775);
WIRE 16 -1 (-2325 3775)(-2325 3725);
WIRE 16 -1 (-2150 3725)(-2325 3725);
WIRE 16 -1 (-2325 3725)(-2325 3675);
WIRE 16 -1 (-2150 3675)(-2325 3675);
WIRE 16 -1 (-2325 3675)(-2325 3625);
WIRE 16 -1 (-2150 3625)(-2325 3625);
WIRE 16 -1 (-2325 3625)(-2325 3575);
WIRE 16 -1 (-2150 3575)(-2325 3575);
WIRE 16 -1 (-2325 3575)(-2325 3525);
WIRE 16 -1 (-2150 3525)(-2325 3525);
WIRE 16 -1 (-2325 3525)(-2325 3475);
WIRE 16 -1 (-2150 3475)(-2325 3475);
WIRE 16 -1 (-2325 3475)(-2325 3425);
WIRE 16 -1 (-2150 3425)(-2325 3425);
WIRE 16 -1 (-2325 3425)(-2325 3375);
WIRE 16 -1 (-2150 3375)(-2325 3375);
WIRE 16 -1 (-2325 3375)(-2325 3325);
WIRE 16 -1 (-2150 3325)(-2325 3325);
WIRE 16 -1 (-2325 3325)(-2325 3275);
WIRE 16 -1 (-2150 3275)(-2325 3275);
WIRE 16 -1 (-2325 3275)(-2325 3225);
WIRE 16 -1 (-2150 3225)(-2325 3225);
WIRE 16 -1 (-2325 3225)(-2325 3175);
WIRE 16 -1 (-2150 3175)(-2325 3175);
WIRE 16 -1 (-2325 3175)(-2325 3125);
WIRE 16 -1 (-2150 3125)(-2325 3125);
WIRE 16 -1 (-2325 3125)(-2325 3075);
WIRE 16 -1 (-2150 3075)(-2325 3075);
WIRE 16 -1 (-2325 3075)(-2325 3025);
WIRE 16 -1 (-2150 3025)(-2325 3025);
WIRE 16 -1 (-2325 3025)(-2325 2975);
WIRE 16 -1 (-2150 2975)(-2325 2975);
WIRE 16 -1 (-2325 2975)(-2325 2925);
WIRE 16 -1 (-2150 2925)(-2325 2925);
WIRE 16 -1 (-2325 2925)(-2325 2875);
WIRE 16 -1 (-2150 2875)(-2325 2875);
WIRE 16 -1 (-2325 2875)(-2325 2825);
WIRE 16 -1 (-2150 2825)(-2325 2825);
WIRE 16 -1 (-2325 2825)(-2325 2775);
WIRE 16 -1 (-2150 2775)(-2325 2775);
WIRE 16 -1 (-2325 2775)(-2325 2725);
WIRE 16 -1 (-2150 2725)(-2325 2725);
WIRE 16 -1 (-2325 2725)(-2325 2675);
WIRE 16 -1 (-2150 2675)(-2325 2675);
WIRE 16 -1 (-2325 2675)(-2325 2625);
WIRE 16 -1 (-2150 2625)(-2325 2625);
WIRE 16 -1 (-2325 2625)(-2325 2575);
WIRE 16 -1 (-2150 2575)(-2325 2575);
WIRE 16 -1 (-2325 2575)(-2325 2525);
WIRE 16 -1 (-2150 2525)(-2325 2525);
WIRE 16 -1 (-2325 2525)(-2325 2475);
WIRE 16 -1 (-2150 2475)(-2325 2475);
WIRE 16 -1 (-2325 2475)(-2325 2425);
WIRE 16 -1 (-2150 2425)(-2325 2425);
WIRE 16 -1 (-2325 2425)(-2325 2375);
WIRE 16 -1 (-2150 2375)(-2325 2375);
WIRE 16 -1 (-2325 2375)(-2325 2325);
WIRE 16 -1 (-2150 2325)(-2325 2325);
WIRE 16 -1 (-2325 2325)(-2325 2275);
WIRE 16 -1 (-2150 2275)(-2325 2275);
WIRE 16 -1 (-2325 2275)(-2325 2225);
WIRE 16 -1 (-2150 2225)(-2325 2225);
WIRE 16 -1 (-2325 2225)(-2325 2175);
WIRE 16 -1 (-2150 2175)(-2325 2175);
WIRE 16 -1 (-2325 2175)(-2325 2125);
WIRE 16 -1 (-2150 2125)(-2325 2125);
WIRE 16 -1 (-2325 2125)(-2325 2075);
WIRE 16 -1 (-2150 2075)(-2325 2075);
WIRE 16 -1 (-2325 2075)(-2325 2025);
WIRE 16 -1 (-2150 2025)(-2325 2025);
WIRE 16 -1 (-2325 2025)(-2325 1975);
WIRE 16 -1 (-2150 1975)(-2325 1975);
WIRE 16 -1 (-2325 1975)(-2325 1925);
WIRE 16 -1 (-2150 1925)(-2325 1925);
WIRE 16 -1 (-2325 1925)(-2325 1875);
WIRE 16 -1 (-2150 1875)(-2325 1875);
WIRE 16 -1 (-2325 1875)(-2325 1825);
WIRE 16 -1 (-2150 1825)(-2325 1825);
WIRE 16 -1 (-2325 1825)(-2325 1775);
WIRE 16 -1 (-2150 1775)(-2325 1775);
WIRE 16 -1 (-2325 1775)(-2325 1725);
WIRE 16 -1 (-2150 1725)(-2325 1725);
WIRE 16 -1 (-2325 1725)(-2325 1675);
WIRE 16 -1 (-2150 1675)(-2325 1675);
WIRE 16 -1 (-2325 1675)(-2325 1625);
WIRE 16 -1 (-2150 1625)(-2325 1625);
WIRE 16 -1 (-2325 1625)(-2325 1575);
WIRE 16 -1 (-2150 1575)(-2325 1575);
WIRE 16 -1 (-2325 1575)(-2325 1525);
WIRE 16 -1 (-2150 1525)(-2325 1525);
WIRE 16 -1 (-2325 1525)(-2325 1475);
WIRE 16 -1 (-2150 1475)(-2325 1475);
WIRE 16 -1 (-2325 1475)(-2325 1425);
WIRE 16 -1 (-2150 1425)(-2325 1425);
WIRE 16 -1 (-2325 1425)(-2325 1375);
WIRE 16 -1 (-2150 1375)(-2325 1375);
WIRE 16 -1 (-2325 1375)(-2325 1325);
WIRE 16 -1 (-2150 1325)(-2325 1325);
WIRE 16 -1 (-2325 1325)(-2325 1275);
WIRE 16 -1 (-2150 1275)(-2325 1275);
WIRE 16 -1 (-2325 1275)(-2325 1225);
WIRE 16 -1 (-2150 1225)(-2325 1225);
WIRE 16 -1 (-2325 1225)(-2325 1175);
WIRE 16 -1 (-2150 1175)(-2325 1175);
WIRE 16 -1 (-2325 1175)(-2325 1125);
WIRE 16 -1 (-2150 1125)(-2325 1125);
WIRE 16 -1 (-2325 1125)(-2325 1075);
WIRE 16 -1 (-2150 1075)(-2325 1075);
WIRE 16 -1 (-2325 1075)(-2325 1025);
WIRE 16 -1 (-2150 1025)(-2325 1025);
WIRE 16 -1 (-2325 1025)(-2325 975);
WIRE 16 -1 (-2150 975)(-2325 975);
WIRE 16 -1 (-2325 975)(-2325 925);
WIRE 16 -1 (-2150 925)(-2325 925);
WIRE 16 -1 (-2325 925)(-2325 875);
WIRE 16 -1 (-2150 875)(-2325 875);
WIRE 16 -1 (-2325 875)(-2325 825);
WIRE 16 -1 (-2325 825)(-2150 825);
WIRE 16 -1 (-2325 825)(-2325 775);
WIRE 16 -1 (-2150 775)(-2325 775);
WIRE 16 -1 (-2325 775)(-2325 725);
WIRE 16 -1 (-2150 725)(-2325 725);
WIRE 16 -1 (-2325 725)(-2325 675);
WIRE 16 -1 (-2150 675)(-2325 675);
WIRE 16 -1 (-2325 675)(-2325 625);
WIRE 16 -1 (-2325 625)(-2150 625);
WIRE 16 -1 (-2325 625)(-2325 525);
WIRE 16 -1 (-7650 4575)(-7800 4575);
WIRE 16 -1 (-7800 4575)(-7800 4525);
WIRE 16 -1 (-7650 4525)(-7800 4525);
WIRE 16 -1 (-7800 4525)(-7800 4475);
WIRE 16 -1 (-7650 4475)(-7800 4475);
WIRE 16 -1 (-7800 4475)(-7800 4425);
WIRE 16 -1 (-7650 4425)(-7800 4425);
WIRE 16 -1 (-7800 4425)(-7800 4375);
WIRE 16 -1 (-7650 4375)(-7800 4375);
WIRE 16 -1 (-7800 4375)(-7800 4325);
WIRE 16 -1 (-7650 4325)(-7800 4325);
WIRE 16 -1 (-7800 4325)(-7800 4275);
WIRE 16 -1 (-7650 4275)(-7800 4275);
WIRE 16 -1 (-7800 4275)(-7800 4225);
WIRE 16 -1 (-7650 4225)(-7800 4225);
WIRE 16 -1 (-7800 4225)(-7800 4175);
WIRE 16 -1 (-7650 4175)(-7800 4175);
WIRE 16 -1 (-7800 4175)(-7800 4125);
WIRE 16 -1 (-7650 4125)(-7800 4125);
WIRE 16 -1 (-7800 4125)(-7800 4075);
WIRE 16 -1 (-7650 4075)(-7800 4075);
WIRE 16 -1 (-7800 4075)(-7800 4025);
WIRE 16 -1 (-7650 4025)(-7800 4025);
WIRE 16 -1 (-7800 4025)(-7800 3975);
WIRE 16 -1 (-7650 3975)(-7800 3975);
WIRE 16 -1 (-7800 3975)(-7800 3925);
WIRE 16 -1 (-7650 3925)(-7800 3925);
WIRE 16 -1 (-7800 3925)(-7800 3875);
WIRE 16 -1 (-7650 3875)(-7800 3875);
WIRE 16 -1 (-7800 3875)(-7800 3825);
WIRE 16 -1 (-7650 3825)(-7800 3825);
WIRE 16 -1 (-7800 3825)(-7800 3775);
WIRE 16 -1 (-7650 3775)(-7800 3775);
WIRE 16 -1 (-7800 3775)(-7800 3725);
WIRE 16 -1 (-7650 3725)(-7800 3725);
WIRE 16 -1 (-7800 3725)(-7800 3675);
WIRE 16 -1 (-7650 3675)(-7800 3675);
WIRE 16 -1 (-7800 3675)(-7800 3625);
WIRE 16 -1 (-7650 3625)(-7800 3625);
WIRE 16 -1 (-7800 3625)(-7800 3575);
WIRE 16 -1 (-7650 3575)(-7800 3575);
WIRE 16 -1 (-7800 3575)(-7800 3525);
WIRE 16 -1 (-7650 3525)(-7800 3525);
WIRE 16 -1 (-7800 3525)(-7800 3475);
WIRE 16 -1 (-7650 3475)(-7800 3475);
WIRE 16 -1 (-7800 3475)(-7800 3425);
WIRE 16 -1 (-7650 3425)(-7800 3425);
WIRE 16 -1 (-7800 3425)(-7800 3375);
WIRE 16 -1 (-7650 3375)(-7800 3375);
WIRE 16 -1 (-7800 3375)(-7800 3325);
WIRE 16 -1 (-7650 3325)(-7800 3325);
WIRE 16 -1 (-7800 3325)(-7800 3275);
WIRE 16 -1 (-7650 3275)(-7800 3275);
WIRE 16 -1 (-7800 3275)(-7800 3225);
WIRE 16 -1 (-7650 3225)(-7800 3225);
WIRE 16 -1 (-7800 3225)(-7800 3175);
WIRE 16 -1 (-7650 3175)(-7800 3175);
WIRE 16 -1 (-7800 3175)(-7800 3125);
WIRE 16 -1 (-7650 3125)(-7800 3125);
WIRE 16 -1 (-7800 3125)(-7800 3075);
WIRE 16 -1 (-7650 3075)(-7800 3075);
WIRE 16 -1 (-7800 3075)(-7800 3025);
WIRE 16 -1 (-7650 3025)(-7800 3025);
WIRE 16 -1 (-7800 3025)(-7800 2975);
WIRE 16 -1 (-7650 2975)(-7800 2975);
WIRE 16 -1 (-7800 2975)(-7800 2925);
WIRE 16 -1 (-7650 2925)(-7800 2925);
WIRE 16 -1 (-7800 2925)(-7800 2875);
WIRE 16 -1 (-7650 2875)(-7800 2875);
WIRE 16 -1 (-7800 2875)(-7800 2825);
WIRE 16 -1 (-7650 2825)(-7800 2825);
WIRE 16 -1 (-7800 2825)(-7800 2775);
WIRE 16 -1 (-7650 2775)(-7800 2775);
WIRE 16 -1 (-7800 2775)(-7800 2725);
WIRE 16 -1 (-7650 2725)(-7800 2725);
WIRE 16 -1 (-7800 2725)(-7800 2675);
WIRE 16 -1 (-7650 2675)(-7800 2675);
WIRE 16 -1 (-7800 2675)(-7800 2625);
WIRE 16 -1 (-7650 2625)(-7800 2625);
WIRE 16 -1 (-7800 2625)(-7800 2575);
WIRE 16 -1 (-7650 2575)(-7800 2575);
WIRE 16 -1 (-7800 2575)(-7800 2525);
WIRE 16 -1 (-7650 2525)(-7800 2525);
WIRE 16 -1 (-7800 2525)(-7800 2475);
WIRE 16 -1 (-7650 2475)(-7800 2475);
WIRE 16 -1 (-7800 2475)(-7800 2425);
WIRE 16 -1 (-7650 2425)(-7800 2425);
WIRE 16 -1 (-7800 2425)(-7800 2375);
WIRE 16 -1 (-7650 2375)(-7800 2375);
WIRE 16 -1 (-7800 2375)(-7800 2325);
WIRE 16 -1 (-7650 2325)(-7800 2325);
WIRE 16 -1 (-7800 2325)(-7800 2275);
WIRE 16 -1 (-7650 2275)(-7800 2275);
WIRE 16 -1 (-7800 2275)(-7800 2225);
WIRE 16 -1 (-7650 2225)(-7800 2225);
WIRE 16 -1 (-7800 2225)(-7800 2175);
WIRE 16 -1 (-7650 2175)(-7800 2175);
WIRE 16 -1 (-7800 2175)(-7800 2125);
WIRE 16 -1 (-7650 2125)(-7800 2125);
WIRE 16 -1 (-7800 2125)(-7800 2075);
WIRE 16 -1 (-7650 2075)(-7800 2075);
WIRE 16 -1 (-7800 2075)(-7800 2025);
WIRE 16 -1 (-7650 2025)(-7800 2025);
WIRE 16 -1 (-7800 2025)(-7800 1975);
WIRE 16 -1 (-7650 1975)(-7800 1975);
WIRE 16 -1 (-7800 1975)(-7800 1925);
WIRE 16 -1 (-7650 1925)(-7800 1925);
WIRE 16 -1 (-7800 1925)(-7800 1875);
WIRE 16 -1 (-7650 1875)(-7800 1875);
WIRE 16 -1 (-7800 1875)(-7800 1825);
WIRE 16 -1 (-7650 1825)(-7800 1825);
WIRE 16 -1 (-7800 1825)(-7800 1775);
WIRE 16 -1 (-7650 1775)(-7800 1775);
WIRE 16 -1 (-7800 1775)(-7800 1725);
WIRE 16 -1 (-7650 1725)(-7800 1725);
WIRE 16 -1 (-7800 1725)(-7800 1675);
WIRE 16 -1 (-7650 1675)(-7800 1675);
WIRE 16 -1 (-7800 1675)(-7800 1625);
WIRE 16 -1 (-7650 1625)(-7800 1625);
WIRE 16 -1 (-7800 1625)(-7800 1575);
WIRE 16 -1 (-7650 1575)(-7800 1575);
WIRE 16 -1 (-7800 1575)(-7800 1525);
WIRE 16 -1 (-7650 1525)(-7800 1525);
WIRE 16 -1 (-7800 1525)(-7800 1475);
WIRE 16 -1 (-7650 1475)(-7800 1475);
WIRE 16 -1 (-7800 1475)(-7800 1425);
WIRE 16 -1 (-7650 1425)(-7800 1425);
WIRE 16 -1 (-7800 1425)(-7800 1375);
WIRE 16 -1 (-7650 1375)(-7800 1375);
WIRE 16 -1 (-7800 1375)(-7800 1325);
WIRE 16 -1 (-7650 1325)(-7800 1325);
WIRE 16 -1 (-7800 1325)(-7800 1275);
WIRE 16 -1 (-7650 1275)(-7800 1275);
WIRE 16 -1 (-7800 1275)(-7800 1225);
WIRE 16 -1 (-7650 1225)(-7800 1225);
WIRE 16 -1 (-7800 1225)(-7800 1175);
WIRE 16 -1 (-7650 1175)(-7800 1175);
WIRE 16 -1 (-7800 1175)(-7800 1125);
WIRE 16 -1 (-7650 1125)(-7800 1125);
WIRE 16 -1 (-7800 1125)(-7800 1075);
WIRE 16 -1 (-7650 1075)(-7800 1075);
WIRE 16 -1 (-7800 1075)(-7800 1025);
WIRE 16 -1 (-7650 1025)(-7800 1025);
WIRE 16 -1 (-7800 1025)(-7800 975);
WIRE 16 -1 (-7650 975)(-7800 975);
WIRE 16 -1 (-7800 975)(-7800 925);
WIRE 16 -1 (-7650 925)(-7800 925);
WIRE 16 -1 (-7800 925)(-7800 875);
WIRE 16 -1 (-7650 875)(-7800 875);
WIRE 16 -1 (-7800 875)(-7800 825);
WIRE 16 -1 (-7650 825)(-7800 825);
WIRE 16 -1 (-7800 825)(-7800 775);
WIRE 16 -1 (-7650 775)(-7800 775);
WIRE 16 -1 (-7800 775)(-7800 725);
WIRE 16 -1 (-7650 725)(-7800 725);
WIRE 16 -1 (-7800 725)(-7800 675);
WIRE 16 -1 (-7650 675)(-7800 675);
WIRE 16 -1 (-7800 675)(-7800 625);
WIRE 16 -1 (-7650 625)(-7800 625);
WIRE 16 -1 (-7800 625)(-7800 500);
WIRE 16 -1 (-5975 4575)(-5825 4575);
WIRE 16 -1 (-5975 4575)(-5975 4525);
WIRE 16 -1 (-5825 4525)(-5975 4525);
WIRE 16 -1 (-5975 4525)(-5975 4475);
WIRE 16 -1 (-5825 4475)(-5975 4475);
WIRE 16 -1 (-5975 4425)(-5975 4475);
WIRE 16 -1 (-5825 4425)(-5975 4425);
WIRE 16 -1 (-5975 4375)(-5975 4425);
WIRE 16 -1 (-5825 4375)(-5975 4375);
WIRE 16 -1 (-5975 4375)(-5975 4325);
WIRE 16 -1 (-5825 4325)(-5975 4325);
WIRE 16 -1 (-5975 4325)(-5975 4275);
WIRE 16 -1 (-5825 4275)(-5975 4275);
WIRE 16 -1 (-5975 4275)(-5975 4225);
WIRE 16 -1 (-5825 4225)(-5975 4225);
WIRE 16 -1 (-5975 4225)(-5975 4175);
WIRE 16 -1 (-5825 4175)(-5975 4175);
WIRE 16 -1 (-5975 4175)(-5975 4125);
WIRE 16 -1 (-5825 4125)(-5975 4125);
WIRE 16 -1 (-5975 4125)(-5975 4075);
WIRE 16 -1 (-5825 4075)(-5975 4075);
WIRE 16 -1 (-5975 4075)(-5975 4025);
WIRE 16 -1 (-5825 4025)(-5975 4025);
WIRE 16 -1 (-5975 4025)(-5975 3975);
WIRE 16 -1 (-5825 3975)(-5975 3975);
WIRE 16 -1 (-5975 3975)(-5975 3925);
WIRE 16 -1 (-5825 3925)(-5975 3925);
WIRE 16 -1 (-5975 3925)(-5975 3875);
WIRE 16 -1 (-5825 3875)(-5975 3875);
WIRE 16 -1 (-5975 3875)(-5975 3825);
WIRE 16 -1 (-5825 3825)(-5975 3825);
WIRE 16 -1 (-5975 3825)(-5975 3775);
WIRE 16 -1 (-5825 3775)(-5975 3775);
WIRE 16 -1 (-5975 3775)(-5975 3725);
WIRE 16 -1 (-5825 3725)(-5975 3725);
WIRE 16 -1 (-5975 3725)(-5975 3675);
WIRE 16 -1 (-5825 3675)(-5975 3675);
WIRE 16 -1 (-5975 3675)(-5975 3625);
WIRE 16 -1 (-5825 3625)(-5975 3625);
WIRE 16 -1 (-5975 3625)(-5975 3575);
WIRE 16 -1 (-5825 3575)(-5975 3575);
WIRE 16 -1 (-5975 3575)(-5975 3525);
WIRE 16 -1 (-5825 3525)(-5975 3525);
WIRE 16 -1 (-5975 3525)(-5975 3475);
WIRE 16 -1 (-5825 3475)(-5975 3475);
WIRE 16 -1 (-5975 3475)(-5975 3425);
WIRE 16 -1 (-5825 3425)(-5975 3425);
WIRE 16 -1 (-5975 3425)(-5975 3375);
WIRE 16 -1 (-5825 3375)(-5975 3375);
WIRE 16 -1 (-5975 3375)(-5975 3325);
WIRE 16 -1 (-5825 3325)(-5975 3325);
WIRE 16 -1 (-5975 3325)(-5975 3275);
WIRE 16 -1 (-5825 3275)(-5975 3275);
WIRE 16 -1 (-5975 3275)(-5975 3225);
WIRE 16 -1 (-5825 3225)(-5975 3225);
WIRE 16 -1 (-5975 3225)(-5975 3175);
WIRE 16 -1 (-5825 3175)(-5975 3175);
WIRE 16 -1 (-5975 3175)(-5975 3125);
WIRE 16 -1 (-5825 3125)(-5975 3125);
WIRE 16 -1 (-5975 3125)(-5975 3075);
WIRE 16 -1 (-5825 3075)(-5975 3075);
WIRE 16 -1 (-5975 3075)(-5975 3025);
WIRE 16 -1 (-5825 3025)(-5975 3025);
WIRE 16 -1 (-5975 3025)(-5975 2975);
WIRE 16 -1 (-5825 2975)(-5975 2975);
WIRE 16 -1 (-5975 2975)(-5975 2925);
WIRE 16 -1 (-5825 2925)(-5975 2925);
WIRE 16 -1 (-5975 2925)(-5975 2875);
WIRE 16 -1 (-5825 2875)(-5975 2875);
WIRE 16 -1 (-5975 2875)(-5975 2825);
WIRE 16 -1 (-5825 2825)(-5975 2825);
WIRE 16 -1 (-5975 2825)(-5975 2775);
WIRE 16 -1 (-5825 2775)(-5975 2775);
WIRE 16 -1 (-5975 2775)(-5975 2725);
WIRE 16 -1 (-5825 2725)(-5975 2725);
WIRE 16 -1 (-5975 2725)(-5975 2675);
WIRE 16 -1 (-5825 2675)(-5975 2675);
WIRE 16 -1 (-5975 2675)(-5975 2625);
WIRE 16 -1 (-5825 2625)(-5975 2625);
WIRE 16 -1 (-5975 2625)(-5975 2575);
WIRE 16 -1 (-5825 2575)(-5975 2575);
WIRE 16 -1 (-5975 2575)(-5975 2525);
WIRE 16 -1 (-5825 2525)(-5975 2525);
WIRE 16 -1 (-5975 2525)(-5975 2475);
WIRE 16 -1 (-5825 2475)(-5975 2475);
WIRE 16 -1 (-5975 2475)(-5975 2425);
WIRE 16 -1 (-5825 2425)(-5975 2425);
WIRE 16 -1 (-5975 2425)(-5975 2375);
WIRE 16 -1 (-5825 2375)(-5975 2375);
WIRE 16 -1 (-5975 2375)(-5975 2325);
WIRE 16 -1 (-5825 2325)(-5975 2325);
WIRE 16 -1 (-5975 2325)(-5975 2275);
WIRE 16 -1 (-5825 2275)(-5975 2275);
WIRE 16 -1 (-5975 2275)(-5975 2225);
WIRE 16 -1 (-5825 2225)(-5975 2225);
WIRE 16 -1 (-5975 2225)(-5975 2175);
WIRE 16 -1 (-5825 2175)(-5975 2175);
WIRE 16 -1 (-5975 2175)(-5975 2125);
WIRE 16 -1 (-5825 2125)(-5975 2125);
WIRE 16 -1 (-5975 2125)(-5975 2075);
WIRE 16 -1 (-5825 2075)(-5975 2075);
WIRE 16 -1 (-5975 2075)(-5975 2025);
WIRE 16 -1 (-5825 2025)(-5975 2025);
WIRE 16 -1 (-5975 2025)(-5975 1975);
WIRE 16 -1 (-5825 1975)(-5975 1975);
WIRE 16 -1 (-5975 1975)(-5975 1925);
WIRE 16 -1 (-5825 1925)(-5975 1925);
WIRE 16 -1 (-5975 1925)(-5975 1875);
WIRE 16 -1 (-5825 1875)(-5975 1875);
WIRE 16 -1 (-5975 1875)(-5975 1825);
WIRE 16 -1 (-5825 1825)(-5975 1825);
WIRE 16 -1 (-5975 1825)(-5975 1775);
WIRE 16 -1 (-5825 1775)(-5975 1775);
WIRE 16 -1 (-5975 1775)(-5975 1725);
WIRE 16 -1 (-5825 1725)(-5975 1725);
WIRE 16 -1 (-5975 1725)(-5975 1675);
WIRE 16 -1 (-5825 1675)(-5975 1675);
WIRE 16 -1 (-5975 1675)(-5975 1625);
WIRE 16 -1 (-5825 1625)(-5975 1625);
WIRE 16 -1 (-5975 1625)(-5975 1575);
WIRE 16 -1 (-5825 1575)(-5975 1575);
WIRE 16 -1 (-5975 1575)(-5975 1525);
WIRE 16 -1 (-5825 1525)(-5975 1525);
WIRE 16 -1 (-5975 1525)(-5975 1475);
WIRE 16 -1 (-5825 1475)(-5975 1475);
WIRE 16 -1 (-5975 1475)(-5975 1425);
WIRE 16 -1 (-5825 1425)(-5975 1425);
WIRE 16 -1 (-5975 1425)(-5975 1375);
WIRE 16 -1 (-5825 1375)(-5975 1375);
WIRE 16 -1 (-5975 1375)(-5975 1325);
WIRE 16 -1 (-5825 1325)(-5975 1325);
WIRE 16 -1 (-5975 1325)(-5975 1275);
WIRE 16 -1 (-5825 1275)(-5975 1275);
WIRE 16 -1 (-5975 1275)(-5975 1225);
WIRE 16 -1 (-5825 1225)(-5975 1225);
WIRE 16 -1 (-5975 1225)(-5975 1175);
WIRE 16 -1 (-5825 1175)(-5975 1175);
WIRE 16 -1 (-5975 1175)(-5975 1125);
WIRE 16 -1 (-5825 1125)(-5975 1125);
WIRE 16 -1 (-5975 1125)(-5975 1075);
WIRE 16 -1 (-5825 1075)(-5975 1075);
WIRE 16 -1 (-5975 1075)(-5975 1025);
WIRE 16 -1 (-5825 1025)(-5975 1025);
WIRE 16 -1 (-5975 1025)(-5975 975);
WIRE 16 -1 (-5825 975)(-5975 975);
WIRE 16 -1 (-5975 975)(-5975 925);
WIRE 16 -1 (-5825 925)(-5975 925);
WIRE 16 -1 (-5975 925)(-5975 875);
WIRE 16 -1 (-5825 875)(-5975 875);
WIRE 16 -1 (-5975 875)(-5975 825);
WIRE 16 -1 (-5825 825)(-5975 825);
WIRE 16 -1 (-5975 825)(-5975 775);
WIRE 16 -1 (-5825 775)(-5975 775);
WIRE 16 -1 (-5975 775)(-5975 725);
WIRE 16 -1 (-5825 725)(-5975 725);
WIRE 16 -1 (-5975 725)(-5975 675);
WIRE 16 -1 (-5825 675)(-5975 675);
WIRE 16 -1 (-5975 675)(-5975 625);
WIRE 16 -1 (-5975 625)(-5825 625);
WIRE 16 -1 (-5975 625)(-5975 500);
WIRE 16 -1 (-6450 4575)(-6275 4575);
WIRE 16 -1 (-6275 4575)(-6275 4525);
WIRE 16 -1 (-6450 4525)(-6275 4525);
WIRE 16 -1 (-6275 4525)(-6275 4475);
WIRE 16 -1 (-6450 4475)(-6275 4475);
WIRE 16 -1 (-6275 4475)(-6275 4425);
WIRE 16 -1 (-6450 4425)(-6275 4425);
WIRE 16 -1 (-6275 4425)(-6275 4375);
WIRE 16 -1 (-6450 4375)(-6275 4375);
WIRE 16 -1 (-6275 4375)(-6275 4325);
WIRE 16 -1 (-6450 4325)(-6275 4325);
WIRE 16 -1 (-6275 4325)(-6275 4275);
WIRE 16 -1 (-6450 4275)(-6275 4275);
WIRE 16 -1 (-6275 4275)(-6275 4225);
WIRE 16 -1 (-6450 4225)(-6275 4225);
WIRE 16 -1 (-6275 4225)(-6275 4175);
WIRE 16 -1 (-6450 4175)(-6275 4175);
WIRE 16 -1 (-6275 4175)(-6275 4125);
WIRE 16 -1 (-6450 4125)(-6275 4125);
WIRE 16 -1 (-6275 4125)(-6275 4075);
WIRE 16 -1 (-6450 4075)(-6275 4075);
WIRE 16 -1 (-6275 4075)(-6275 4025);
WIRE 16 -1 (-6450 4025)(-6275 4025);
WIRE 16 -1 (-6275 4025)(-6275 3975);
WIRE 16 -1 (-6450 3975)(-6275 3975);
WIRE 16 -1 (-6275 3975)(-6275 3925);
WIRE 16 -1 (-6450 3925)(-6275 3925);
WIRE 16 -1 (-6275 3925)(-6275 3875);
WIRE 16 -1 (-6450 3875)(-6275 3875);
WIRE 16 -1 (-6275 3875)(-6275 3825);
WIRE 16 -1 (-6450 3825)(-6275 3825);
WIRE 16 -1 (-6275 3825)(-6275 3775);
WIRE 16 -1 (-6450 3775)(-6275 3775);
WIRE 16 -1 (-6275 3775)(-6275 3725);
WIRE 16 -1 (-6450 3725)(-6275 3725);
WIRE 16 -1 (-6275 3725)(-6275 3675);
WIRE 16 -1 (-6450 3675)(-6275 3675);
WIRE 16 -1 (-6275 3675)(-6275 3625);
WIRE 16 -1 (-6450 3625)(-6275 3625);
WIRE 16 -1 (-6275 3625)(-6275 3575);
WIRE 16 -1 (-6450 3575)(-6275 3575);
WIRE 16 -1 (-6275 3575)(-6275 3525);
WIRE 16 -1 (-6450 3525)(-6275 3525);
WIRE 16 -1 (-6275 3525)(-6275 3475);
WIRE 16 -1 (-6450 3475)(-6275 3475);
WIRE 16 -1 (-6275 3475)(-6275 3425);
WIRE 16 -1 (-6450 3425)(-6275 3425);
WIRE 16 -1 (-6275 3425)(-6275 3375);
WIRE 16 -1 (-6450 3375)(-6275 3375);
WIRE 16 -1 (-6275 3375)(-6275 3325);
WIRE 16 -1 (-6450 3325)(-6275 3325);
WIRE 16 -1 (-6275 3325)(-6275 3275);
WIRE 16 -1 (-6450 3275)(-6275 3275);
WIRE 16 -1 (-6275 3275)(-6275 3225);
WIRE 16 -1 (-6450 3225)(-6275 3225);
WIRE 16 -1 (-6275 3225)(-6275 3175);
WIRE 16 -1 (-6450 3175)(-6275 3175);
WIRE 16 -1 (-6275 3175)(-6275 3125);
WIRE 16 -1 (-6450 3125)(-6275 3125);
WIRE 16 -1 (-6275 3125)(-6275 3075);
WIRE 16 -1 (-6450 3075)(-6275 3075);
WIRE 16 -1 (-6275 3075)(-6275 3025);
WIRE 16 -1 (-6450 3025)(-6275 3025);
WIRE 16 -1 (-6275 3025)(-6275 2975);
WIRE 16 -1 (-6450 2975)(-6275 2975);
WIRE 16 -1 (-6275 2975)(-6275 2925);
WIRE 16 -1 (-6450 2925)(-6275 2925);
WIRE 16 -1 (-6275 2925)(-6275 2875);
WIRE 16 -1 (-6450 2875)(-6275 2875);
WIRE 16 -1 (-6275 2875)(-6275 2825);
WIRE 16 -1 (-6450 2825)(-6275 2825);
WIRE 16 -1 (-6275 2825)(-6275 2775);
WIRE 16 -1 (-6450 2775)(-6275 2775);
WIRE 16 -1 (-6275 2775)(-6275 2725);
WIRE 16 -1 (-6450 2725)(-6275 2725);
WIRE 16 -1 (-6275 2725)(-6275 2675);
WIRE 16 -1 (-6450 2675)(-6275 2675);
WIRE 16 -1 (-6275 2675)(-6275 2625);
WIRE 16 -1 (-6450 2625)(-6275 2625);
WIRE 16 -1 (-6275 2625)(-6275 2575);
WIRE 16 -1 (-6450 2575)(-6275 2575);
WIRE 16 -1 (-6275 2575)(-6275 2525);
WIRE 16 -1 (-6450 2525)(-6275 2525);
WIRE 16 -1 (-6275 2525)(-6275 2475);
WIRE 16 -1 (-6450 2475)(-6275 2475);
WIRE 16 -1 (-6275 2475)(-6275 2425);
WIRE 16 -1 (-6450 2425)(-6275 2425);
WIRE 16 -1 (-6275 2425)(-6275 2375);
WIRE 16 -1 (-6450 2375)(-6275 2375);
WIRE 16 -1 (-6275 2375)(-6275 2325);
WIRE 16 -1 (-6450 2325)(-6275 2325);
WIRE 16 -1 (-6275 2325)(-6275 2275);
WIRE 16 -1 (-6450 2275)(-6275 2275);
WIRE 16 -1 (-6275 2275)(-6275 2225);
WIRE 16 -1 (-6450 2225)(-6275 2225);
WIRE 16 -1 (-6275 2225)(-6275 2175);
WIRE 16 -1 (-6450 2175)(-6275 2175);
WIRE 16 -1 (-6275 2175)(-6275 2125);
WIRE 16 -1 (-6450 2125)(-6275 2125);
WIRE 16 -1 (-6275 2125)(-6275 2075);
WIRE 16 -1 (-6450 2075)(-6275 2075);
WIRE 16 -1 (-6275 2075)(-6275 2025);
WIRE 16 -1 (-6450 2025)(-6275 2025);
WIRE 16 -1 (-6275 2025)(-6275 1975);
WIRE 16 -1 (-6450 1975)(-6275 1975);
WIRE 16 -1 (-6275 1975)(-6275 1925);
WIRE 16 -1 (-6450 1925)(-6275 1925);
WIRE 16 -1 (-6275 1925)(-6275 1875);
WIRE 16 -1 (-6450 1875)(-6275 1875);
WIRE 16 -1 (-6275 1875)(-6275 1825);
WIRE 16 -1 (-6450 1825)(-6275 1825);
WIRE 16 -1 (-6275 1825)(-6275 1775);
WIRE 16 -1 (-6450 1775)(-6275 1775);
WIRE 16 -1 (-6275 1775)(-6275 1725);
WIRE 16 -1 (-6450 1725)(-6275 1725);
WIRE 16 -1 (-6275 1725)(-6275 1675);
WIRE 16 -1 (-6450 1675)(-6275 1675);
WIRE 16 -1 (-6275 1675)(-6275 1625);
WIRE 16 -1 (-6450 1625)(-6275 1625);
WIRE 16 -1 (-6275 1625)(-6275 1575);
WIRE 16 -1 (-6450 1575)(-6275 1575);
WIRE 16 -1 (-6275 1575)(-6275 1525);
WIRE 16 -1 (-6450 1525)(-6275 1525);
WIRE 16 -1 (-6275 1525)(-6275 1475);
WIRE 16 -1 (-6450 1475)(-6275 1475);
WIRE 16 -1 (-6275 1475)(-6275 1425);
WIRE 16 -1 (-6450 1425)(-6275 1425);
WIRE 16 -1 (-6275 1425)(-6275 1375);
WIRE 16 -1 (-6450 1375)(-6275 1375);
WIRE 16 -1 (-6275 1375)(-6275 1325);
WIRE 16 -1 (-6450 1325)(-6275 1325);
WIRE 16 -1 (-6275 1325)(-6275 1275);
WIRE 16 -1 (-6450 1275)(-6275 1275);
WIRE 16 -1 (-6275 1275)(-6275 1225);
WIRE 16 -1 (-6450 1225)(-6275 1225);
WIRE 16 -1 (-6275 1225)(-6275 1175);
WIRE 16 -1 (-6450 1175)(-6275 1175);
WIRE 16 -1 (-6275 1175)(-6275 1125);
WIRE 16 -1 (-6450 1125)(-6275 1125);
WIRE 16 -1 (-6275 1125)(-6275 1075);
WIRE 16 -1 (-6450 1075)(-6275 1075);
WIRE 16 -1 (-6275 1075)(-6275 1025);
WIRE 16 -1 (-6450 1025)(-6275 1025);
WIRE 16 -1 (-6275 1025)(-6275 975);
WIRE 16 -1 (-6450 975)(-6275 975);
WIRE 16 -1 (-6275 975)(-6275 925);
WIRE 16 -1 (-6450 925)(-6275 925);
WIRE 16 -1 (-6275 925)(-6275 875);
WIRE 16 -1 (-6450 875)(-6275 875);
WIRE 16 -1 (-6275 875)(-6275 825);
WIRE 16 -1 (-6450 825)(-6275 825);
WIRE 16 -1 (-6275 825)(-6275 775);
WIRE 16 -1 (-6450 775)(-6275 775);
WIRE 16 -1 (-6275 775)(-6275 725);
WIRE 16 -1 (-6450 725)(-6275 725);
WIRE 16 -1 (-6275 725)(-6275 675);
WIRE 16 -1 (-6450 675)(-6275 675);
WIRE 16 -1 (-6275 675)(-6275 625);
WIRE 16 -1 (-6450 625)(-6275 625);
WIRE 16 -1 (-6275 625)(-6275 500);
WIRE 16 -1 (-4450 4575)(-4450 4525);
WIRE 16 -1 (-4450 4575)(-4625 4575);
WIRE 16 -1 (-4625 4525)(-4450 4525);
WIRE 16 -1 (-4450 4525)(-4450 4475);
WIRE 16 -1 (-4625 4475)(-4450 4475);
WIRE 16 -1 (-4450 4475)(-4450 4425);
WIRE 16 -1 (-4625 4425)(-4450 4425);
WIRE 16 -1 (-4450 4425)(-4450 4375);
WIRE 16 -1 (-4625 4375)(-4450 4375);
WIRE 16 -1 (-4450 4375)(-4450 4325);
WIRE 16 -1 (-4625 4325)(-4450 4325);
WIRE 16 -1 (-4450 4325)(-4450 4275);
WIRE 16 -1 (-4625 4275)(-4450 4275);
WIRE 16 -1 (-4450 4275)(-4450 4225);
WIRE 16 -1 (-4625 4225)(-4450 4225);
WIRE 16 -1 (-4450 4225)(-4450 4175);
WIRE 16 -1 (-4625 4175)(-4450 4175);
WIRE 16 -1 (-4450 4175)(-4450 4125);
WIRE 16 -1 (-4625 4125)(-4450 4125);
WIRE 16 -1 (-4450 4125)(-4450 4075);
WIRE 16 -1 (-4625 4075)(-4450 4075);
WIRE 16 -1 (-4450 4075)(-4450 4025);
WIRE 16 -1 (-4625 4025)(-4450 4025);
WIRE 16 -1 (-4450 4025)(-4450 3975);
WIRE 16 -1 (-4625 3975)(-4450 3975);
WIRE 16 -1 (-4450 3975)(-4450 3925);
WIRE 16 -1 (-4625 3925)(-4450 3925);
WIRE 16 -1 (-4450 3925)(-4450 3875);
WIRE 16 -1 (-4625 3875)(-4450 3875);
WIRE 16 -1 (-4450 3875)(-4450 3825);
WIRE 16 -1 (-4625 3825)(-4450 3825);
WIRE 16 -1 (-4450 3825)(-4450 3775);
WIRE 16 -1 (-4625 3775)(-4450 3775);
WIRE 16 -1 (-4450 3775)(-4450 3725);
WIRE 16 -1 (-4625 3725)(-4450 3725);
WIRE 16 -1 (-4450 3725)(-4450 3675);
WIRE 16 -1 (-4625 3675)(-4450 3675);
WIRE 16 -1 (-4450 3675)(-4450 3625);
WIRE 16 -1 (-4625 3625)(-4450 3625);
WIRE 16 -1 (-4450 3625)(-4450 3575);
WIRE 16 -1 (-4625 3575)(-4450 3575);
WIRE 16 -1 (-4450 3575)(-4450 3525);
WIRE 16 -1 (-4625 3525)(-4450 3525);
WIRE 16 -1 (-4450 3525)(-4450 3475);
WIRE 16 -1 (-4625 3475)(-4450 3475);
WIRE 16 -1 (-4450 3475)(-4450 3425);
WIRE 16 -1 (-4625 3425)(-4450 3425);
WIRE 16 -1 (-4450 3425)(-4450 3375);
WIRE 16 -1 (-4625 3375)(-4450 3375);
WIRE 16 -1 (-4450 3375)(-4450 3325);
WIRE 16 -1 (-4625 3325)(-4450 3325);
WIRE 16 -1 (-4450 3325)(-4450 3275);
WIRE 16 -1 (-4625 3275)(-4450 3275);
WIRE 16 -1 (-4450 3275)(-4450 3225);
WIRE 16 -1 (-4625 3225)(-4450 3225);
WIRE 16 -1 (-4450 3225)(-4450 3175);
WIRE 16 -1 (-4625 3175)(-4450 3175);
WIRE 16 -1 (-4450 3175)(-4450 3125);
WIRE 16 -1 (-4625 3125)(-4450 3125);
WIRE 16 -1 (-4450 3125)(-4450 3075);
WIRE 16 -1 (-4625 3075)(-4450 3075);
WIRE 16 -1 (-4450 3075)(-4450 3025);
WIRE 16 -1 (-4625 3025)(-4450 3025);
WIRE 16 -1 (-4450 3025)(-4450 2975);
WIRE 16 -1 (-4625 2975)(-4450 2975);
WIRE 16 -1 (-4450 2975)(-4450 2925);
WIRE 16 -1 (-4625 2925)(-4450 2925);
WIRE 16 -1 (-4450 2925)(-4450 2875);
WIRE 16 -1 (-4625 2875)(-4450 2875);
WIRE 16 -1 (-4450 2875)(-4450 2825);
WIRE 16 -1 (-4625 2825)(-4450 2825);
WIRE 16 -1 (-4450 2825)(-4450 2775);
WIRE 16 -1 (-4625 2775)(-4450 2775);
WIRE 16 -1 (-4450 2775)(-4450 2725);
WIRE 16 -1 (-4625 2725)(-4450 2725);
WIRE 16 -1 (-4450 2725)(-4450 2675);
WIRE 16 -1 (-4625 2675)(-4450 2675);
WIRE 16 -1 (-4450 2675)(-4450 2625);
WIRE 16 -1 (-4625 2625)(-4450 2625);
WIRE 16 -1 (-4450 2625)(-4450 2575);
WIRE 16 -1 (-4625 2575)(-4450 2575);
WIRE 16 -1 (-4450 2575)(-4450 2525);
WIRE 16 -1 (-4625 2525)(-4450 2525);
WIRE 16 -1 (-4450 2525)(-4450 2475);
WIRE 16 -1 (-4625 2475)(-4450 2475);
WIRE 16 -1 (-4450 2475)(-4450 2425);
WIRE 16 -1 (-4625 2425)(-4450 2425);
WIRE 16 -1 (-4450 2425)(-4450 2375);
WIRE 16 -1 (-4625 2375)(-4450 2375);
WIRE 16 -1 (-4450 2375)(-4450 2325);
WIRE 16 -1 (-4625 2325)(-4450 2325);
WIRE 16 -1 (-4450 2325)(-4450 2275);
WIRE 16 -1 (-4625 2275)(-4450 2275);
WIRE 16 -1 (-4450 2275)(-4450 2225);
WIRE 16 -1 (-4625 2225)(-4450 2225);
WIRE 16 -1 (-4450 2225)(-4450 2175);
WIRE 16 -1 (-4625 2175)(-4450 2175);
WIRE 16 -1 (-4450 2175)(-4450 2125);
WIRE 16 -1 (-4625 2125)(-4450 2125);
WIRE 16 -1 (-4450 2125)(-4450 2075);
WIRE 16 -1 (-4625 2075)(-4450 2075);
WIRE 16 -1 (-4450 2075)(-4450 2025);
WIRE 16 -1 (-4625 2025)(-4450 2025);
WIRE 16 -1 (-4450 2025)(-4450 1975);
WIRE 16 -1 (-4625 1975)(-4450 1975);
WIRE 16 -1 (-4450 1975)(-4450 1925);
WIRE 16 -1 (-4625 1925)(-4450 1925);
WIRE 16 -1 (-4450 1925)(-4450 1875);
WIRE 16 -1 (-4625 1875)(-4450 1875);
WIRE 16 -1 (-4450 1875)(-4450 1825);
WIRE 16 -1 (-4625 1825)(-4450 1825);
WIRE 16 -1 (-4450 1825)(-4450 1775);
WIRE 16 -1 (-4625 1775)(-4450 1775);
WIRE 16 -1 (-4450 1775)(-4450 1725);
WIRE 16 -1 (-4625 1725)(-4450 1725);
WIRE 16 -1 (-4450 1725)(-4450 1675);
WIRE 16 -1 (-4625 1675)(-4450 1675);
WIRE 16 -1 (-4450 1675)(-4450 1625);
WIRE 16 -1 (-4625 1625)(-4450 1625);
WIRE 16 -1 (-4450 1625)(-4450 1575);
WIRE 16 -1 (-4625 1575)(-4450 1575);
WIRE 16 -1 (-4450 1575)(-4450 1525);
WIRE 16 -1 (-4625 1525)(-4450 1525);
WIRE 16 -1 (-4450 1525)(-4450 1475);
WIRE 16 -1 (-4625 1475)(-4450 1475);
WIRE 16 -1 (-4450 1475)(-4450 1425);
WIRE 16 -1 (-4625 1425)(-4450 1425);
WIRE 16 -1 (-4450 1425)(-4450 1375);
WIRE 16 -1 (-4625 1375)(-4450 1375);
WIRE 16 -1 (-4450 1375)(-4450 1325);
WIRE 16 -1 (-4625 1325)(-4450 1325);
WIRE 16 -1 (-4450 1325)(-4450 1275);
WIRE 16 -1 (-4625 1275)(-4450 1275);
WIRE 16 -1 (-4450 1275)(-4450 1225);
WIRE 16 -1 (-4625 1225)(-4450 1225);
WIRE 16 -1 (-4450 1225)(-4450 1175);
WIRE 16 -1 (-4625 1175)(-4450 1175);
WIRE 16 -1 (-4450 1175)(-4450 1125);
WIRE 16 -1 (-4625 1125)(-4450 1125);
WIRE 16 -1 (-4450 1125)(-4450 1075);
WIRE 16 -1 (-4625 1075)(-4450 1075);
WIRE 16 -1 (-4450 1075)(-4450 1025);
WIRE 16 -1 (-4625 1025)(-4450 1025);
WIRE 16 -1 (-4450 1025)(-4450 975);
WIRE 16 -1 (-4625 975)(-4450 975);
WIRE 16 -1 (-4450 975)(-4450 925);
WIRE 16 -1 (-4625 925)(-4450 925);
WIRE 16 -1 (-4450 925)(-4450 875);
WIRE 16 -1 (-4625 875)(-4450 875);
WIRE 16 -1 (-4450 875)(-4450 825);
WIRE 16 -1 (-4625 825)(-4450 825);
WIRE 16 -1 (-4450 825)(-4450 775);
WIRE 16 -1 (-4625 775)(-4450 775);
WIRE 16 -1 (-4450 775)(-4450 725);
WIRE 16 -1 (-4625 725)(-4450 725);
WIRE 16 -1 (-4450 725)(-4450 675);
WIRE 16 -1 (-4625 675)(-4450 675);
WIRE 16 -1 (-4450 675)(-4450 625);
WIRE 16 -1 (-4625 625)(-4450 625);
WIRE 16 -1 (-4450 625)(-4450 500);
WIRE 16 -1 (-4150 4575)(-4000 4575);
WIRE 16 -1 (-4150 4575)(-4150 4525);
WIRE 16 -1 (-4000 4525)(-4150 4525);
WIRE 16 -1 (-4150 4525)(-4150 4475);
WIRE 16 -1 (-4000 4475)(-4150 4475);
WIRE 16 -1 (-4150 4475)(-4150 4425);
WIRE 16 -1 (-4000 4425)(-4150 4425);
WIRE 16 -1 (-4150 4425)(-4150 4375);
WIRE 16 -1 (-4000 4375)(-4150 4375);
WIRE 16 -1 (-4150 4375)(-4150 4325);
WIRE 16 -1 (-4000 4325)(-4150 4325);
WIRE 16 -1 (-4150 4325)(-4150 4275);
WIRE 16 -1 (-4000 4275)(-4150 4275);
WIRE 16 -1 (-4150 4275)(-4150 4225);
WIRE 16 -1 (-4000 4225)(-4150 4225);
WIRE 16 -1 (-4150 4225)(-4150 4175);
WIRE 16 -1 (-4000 4175)(-4150 4175);
WIRE 16 -1 (-4150 4175)(-4150 4125);
WIRE 16 -1 (-4000 4125)(-4150 4125);
WIRE 16 -1 (-4150 4125)(-4150 4075);
WIRE 16 -1 (-4000 4075)(-4150 4075);
WIRE 16 -1 (-4150 4075)(-4150 4025);
WIRE 16 -1 (-4000 4025)(-4150 4025);
WIRE 16 -1 (-4150 4025)(-4150 3975);
WIRE 16 -1 (-4000 3975)(-4150 3975);
WIRE 16 -1 (-4150 3975)(-4150 3925);
WIRE 16 -1 (-4000 3925)(-4150 3925);
WIRE 16 -1 (-4150 3925)(-4150 3875);
WIRE 16 -1 (-4000 3875)(-4150 3875);
WIRE 16 -1 (-4150 3875)(-4150 3825);
WIRE 16 -1 (-4000 3825)(-4150 3825);
WIRE 16 -1 (-4150 3825)(-4150 3775);
WIRE 16 -1 (-4000 3775)(-4150 3775);
WIRE 16 -1 (-4150 3775)(-4150 3725);
WIRE 16 -1 (-4000 3725)(-4150 3725);
WIRE 16 -1 (-4150 3725)(-4150 3675);
WIRE 16 -1 (-4000 3675)(-4150 3675);
WIRE 16 -1 (-4150 3675)(-4150 3625);
WIRE 16 -1 (-4000 3625)(-4150 3625);
WIRE 16 -1 (-4150 3625)(-4150 3575);
WIRE 16 -1 (-4000 3575)(-4150 3575);
WIRE 16 -1 (-4150 3575)(-4150 3525);
WIRE 16 -1 (-4000 3525)(-4150 3525);
WIRE 16 -1 (-4150 3525)(-4150 3475);
WIRE 16 -1 (-4000 3475)(-4150 3475);
WIRE 16 -1 (-4150 3475)(-4150 3425);
WIRE 16 -1 (-4000 3425)(-4150 3425);
WIRE 16 -1 (-4150 3425)(-4150 3375);
WIRE 16 -1 (-4000 3375)(-4150 3375);
WIRE 16 -1 (-4150 3375)(-4150 3325);
WIRE 16 -1 (-4000 3325)(-4150 3325);
WIRE 16 -1 (-4150 3325)(-4150 3275);
WIRE 16 -1 (-4000 3275)(-4150 3275);
WIRE 16 -1 (-4150 3275)(-4150 3225);
WIRE 16 -1 (-4000 3225)(-4150 3225);
WIRE 16 -1 (-4150 3225)(-4150 3175);
WIRE 16 -1 (-4000 3175)(-4150 3175);
WIRE 16 -1 (-4150 3175)(-4150 3125);
WIRE 16 -1 (-4000 3125)(-4150 3125);
WIRE 16 -1 (-4150 3125)(-4150 3075);
WIRE 16 -1 (-4000 3075)(-4150 3075);
WIRE 16 -1 (-4150 3075)(-4150 3025);
WIRE 16 -1 (-4000 3025)(-4150 3025);
WIRE 16 -1 (-4150 3025)(-4150 2975);
WIRE 16 -1 (-4000 2975)(-4150 2975);
WIRE 16 -1 (-4150 2975)(-4150 2925);
WIRE 16 -1 (-4000 2925)(-4150 2925);
WIRE 16 -1 (-4150 2925)(-4150 2875);
WIRE 16 -1 (-4000 2875)(-4150 2875);
WIRE 16 -1 (-4150 2875)(-4150 2825);
WIRE 16 -1 (-4000 2825)(-4150 2825);
WIRE 16 -1 (-4150 2825)(-4150 2775);
WIRE 16 -1 (-4000 2775)(-4150 2775);
WIRE 16 -1 (-4150 2775)(-4150 2725);
WIRE 16 -1 (-4000 2725)(-4150 2725);
WIRE 16 -1 (-4150 2725)(-4150 2675);
WIRE 16 -1 (-4000 2675)(-4150 2675);
WIRE 16 -1 (-4150 2675)(-4150 2625);
WIRE 16 -1 (-4000 2625)(-4150 2625);
WIRE 16 -1 (-4150 2625)(-4150 2575);
WIRE 16 -1 (-4000 2575)(-4150 2575);
WIRE 16 -1 (-4150 2575)(-4150 2525);
WIRE 16 -1 (-4000 2525)(-4150 2525);
WIRE 16 -1 (-4150 2525)(-4150 2475);
WIRE 16 -1 (-4000 2475)(-4150 2475);
WIRE 16 -1 (-4150 2475)(-4150 2425);
WIRE 16 -1 (-4000 2425)(-4150 2425);
WIRE 16 -1 (-4150 2425)(-4150 2375);
WIRE 16 -1 (-4000 2375)(-4150 2375);
WIRE 16 -1 (-4150 2375)(-4150 2325);
WIRE 16 -1 (-4000 2325)(-4150 2325);
WIRE 16 -1 (-4150 2325)(-4150 2275);
WIRE 16 -1 (-4000 2275)(-4150 2275);
WIRE 16 -1 (-4150 2275)(-4150 2225);
WIRE 16 -1 (-4000 2225)(-4150 2225);
WIRE 16 -1 (-4150 2225)(-4150 2175);
WIRE 16 -1 (-4000 2175)(-4150 2175);
WIRE 16 -1 (-4150 2175)(-4150 2125);
WIRE 16 -1 (-4000 2125)(-4150 2125);
WIRE 16 -1 (-4150 2125)(-4150 2075);
WIRE 16 -1 (-4000 2075)(-4150 2075);
WIRE 16 -1 (-4150 2075)(-4150 2025);
WIRE 16 -1 (-4000 2025)(-4150 2025);
WIRE 16 -1 (-4150 2025)(-4150 1975);
WIRE 16 -1 (-4000 1975)(-4150 1975);
WIRE 16 -1 (-4150 1975)(-4150 1925);
WIRE 16 -1 (-4000 1925)(-4150 1925);
WIRE 16 -1 (-4150 1925)(-4150 1875);
WIRE 16 -1 (-4000 1875)(-4150 1875);
WIRE 16 -1 (-4150 1875)(-4150 1825);
WIRE 16 -1 (-4000 1825)(-4150 1825);
WIRE 16 -1 (-4150 1825)(-4150 1775);
WIRE 16 -1 (-4000 1775)(-4150 1775);
WIRE 16 -1 (-4150 1775)(-4150 1725);
WIRE 16 -1 (-4000 1725)(-4150 1725);
WIRE 16 -1 (-4150 1725)(-4150 1675);
WIRE 16 -1 (-4000 1675)(-4150 1675);
WIRE 16 -1 (-4150 1675)(-4150 1625);
WIRE 16 -1 (-4000 1625)(-4150 1625);
WIRE 16 -1 (-4150 1625)(-4150 1575);
WIRE 16 -1 (-4000 1575)(-4150 1575);
WIRE 16 -1 (-4150 1575)(-4150 1525);
WIRE 16 -1 (-4000 1525)(-4150 1525);
WIRE 16 -1 (-4150 1525)(-4150 1475);
WIRE 16 -1 (-4000 1475)(-4150 1475);
WIRE 16 -1 (-4150 1475)(-4150 1425);
WIRE 16 -1 (-4000 1425)(-4150 1425);
WIRE 16 -1 (-4150 1425)(-4150 1375);
WIRE 16 -1 (-4000 1375)(-4150 1375);
WIRE 16 -1 (-4150 1375)(-4150 1325);
WIRE 16 -1 (-4000 1325)(-4150 1325);
WIRE 16 -1 (-4150 1325)(-4150 1275);
WIRE 16 -1 (-4000 1275)(-4150 1275);
WIRE 16 -1 (-4150 1275)(-4150 1225);
WIRE 16 -1 (-4000 1225)(-4150 1225);
WIRE 16 -1 (-4150 1225)(-4150 1175);
WIRE 16 -1 (-4000 1175)(-4150 1175);
WIRE 16 -1 (-4150 1175)(-4150 1125);
WIRE 16 -1 (-4000 1125)(-4150 1125);
WIRE 16 -1 (-4150 1125)(-4150 1075);
WIRE 16 -1 (-4000 1075)(-4150 1075);
WIRE 16 -1 (-4150 1075)(-4150 1025);
WIRE 16 -1 (-4000 1025)(-4150 1025);
WIRE 16 -1 (-4150 1025)(-4150 975);
WIRE 16 -1 (-4000 975)(-4150 975);
WIRE 16 -1 (-4150 975)(-4150 925);
WIRE 16 -1 (-4000 925)(-4150 925);
WIRE 16 -1 (-4150 925)(-4150 875);
WIRE 16 -1 (-4000 875)(-4150 875);
WIRE 16 -1 (-4150 875)(-4150 825);
WIRE 16 -1 (-4000 825)(-4150 825);
WIRE 16 -1 (-4150 825)(-4150 775);
WIRE 16 -1 (-4000 775)(-4150 775);
WIRE 16 -1 (-4150 775)(-4150 725);
WIRE 16 -1 (-4000 725)(-4150 725);
WIRE 16 -1 (-4150 725)(-4150 675);
WIRE 16 -1 (-4000 675)(-4150 675);
WIRE 16 -1 (-4150 675)(-4150 625);
WIRE 16 -1 (-4150 625)(-4000 625);
WIRE 16 -1 (-4150 625)(-4150 500);
DOT 1 (-6275 3625);
DOT 1 (-6275 4075);
DOT 1 (-5975 4375);
DOT 1 (-5975 4425);
DOT 1 (-5975 3875);
DOT 1 (-5975 3725);
DOT 1 (-5975 3575);
DOT 1 (-4150 1375);
DOT 1 (-4150 3925);
DOT 1 (-5975 4475);
DOT 1 (-5975 4325);
DOT 1 (-5975 4275);
DOT 1 (-6275 4325);
DOT 1 (-6275 3975);
DOT 1 (-6275 4175);
DOT 1 (-6275 3175);
DOT 1 (-6275 2625);
DOT 1 (-6275 2125);
DOT 1 (-6275 1625);
DOT 1 (-5975 675);
DOT 1 (-6275 875);
DOT 1 (-6275 2825);
DOT 1 (-4150 3625);
DOT 1 (-6275 3275);
DOT 1 (-2325 2375);
DOT 1 (-775 1625);
DOT 1 (-2625 1525);
DOT 1 (-4450 1725);
DOT 1 (-4450 1675);
DOT 1 (-5975 1675);
DOT 1 (-4150 2575);
DOT 1 (-4150 2625);
DOT 1 (-4150 2675);
DOT 1 (-4150 2725);
DOT 1 (-5975 3275);
DOT 1 (-5975 2675);
DOT 1 (-5975 2475);
DOT 1 (-5975 2275);
DOT 1 (-5975 2075);
DOT 1 (-5975 2025);
DOT 1 (-5975 1725);
DOT 1 (-5975 1775);
DOT 1 (-5975 1925);
DOT 1 (-6275 4525);
DOT 1 (-4450 4225);
DOT 1 (-4150 1325);
DOT 1 (-2625 1925);
DOT 1 (-6275 1275);
DOT 1 (-4450 3675);
DOT 1 (-5975 3525);
DOT 1 (-4450 3725);
DOT 1 (-2325 625);
DOT 1 (-2325 675);
DOT 1 (-2325 725);
DOT 1 (-2325 775);
DOT 1 (-2625 1625);
DOT 1 (-2625 1675);
DOT 1 (-2325 825);
DOT 1 (-2325 875);
DOT 1 (-2325 925);
DOT 1 (-2625 1425);
DOT 1 (-4150 2425);
DOT 1 (-4150 2375);
DOT 1 (-2625 975);
DOT 1 (-2625 875);
DOT 1 (-2625 825);
DOT 1 (-2625 775);
DOT 1 (-2625 725);
DOT 1 (-775 625);
DOT 1 (-775 675);
DOT 1 (-775 725);
DOT 1 (-775 775);
DOT 1 (-775 875);
DOT 1 (-775 825);
DOT 1 (-775 975);
DOT 1 (-775 925);
DOT 1 (-775 1025);
DOT 1 (-775 1125);
DOT 1 (-775 1075);
DOT 1 (-775 1225);
DOT 1 (-775 1275);
DOT 1 (-775 1175);
DOT 1 (-775 1325);
DOT 1 (-775 1375);
DOT 1 (-775 1475);
DOT 1 (-775 1525);
DOT 1 (-775 1425);
DOT 1 (-775 1575);
DOT 1 (-775 1675);
DOT 1 (-775 1775);
DOT 1 (-775 1725);
DOT 1 (-775 1875);
DOT 1 (-775 1825);
DOT 1 (-775 1925);
DOT 1 (-775 2025);
DOT 1 (-775 1975);
DOT 1 (-775 2175);
DOT 1 (-775 2125);
DOT 1 (-775 2075);
DOT 1 (-775 2225);
DOT 1 (-775 2275);
DOT 1 (-775 2425);
DOT 1 (-775 2375);
DOT 1 (-775 2325);
DOT 1 (-775 2475);
DOT 1 (-775 2525);
DOT 1 (-775 2675);
DOT 1 (-775 2625);
DOT 1 (-775 2575);
DOT 1 (-775 2725);
DOT 1 (-775 2775);
DOT 1 (-775 2825);
DOT 1 (-775 2925);
DOT 1 (-775 2875);
DOT 1 (-775 3025);
DOT 1 (-775 2975);
DOT 1 (-775 3075);
DOT 1 (-775 3175);
DOT 1 (-775 3125);
DOT 1 (-775 3275);
DOT 1 (-775 3325);
DOT 1 (-775 3225);
DOT 1 (-775 3425);
DOT 1 (-775 3375);
DOT 1 (-775 3525);
DOT 1 (-775 3575);
DOT 1 (-775 3475);
DOT 1 (-775 3675);
DOT 1 (-775 3725);
DOT 1 (-775 3825);
DOT 1 (-775 3775);
DOT 1 (-775 3925);
DOT 1 (-775 3875);
DOT 1 (-775 3975);
DOT 1 (-775 4075);
DOT 1 (-775 4025);
DOT 1 (-775 4175);
DOT 1 (-775 4125);
DOT 1 (-775 4225);
DOT 1 (-775 4325);
DOT 1 (-775 4275);
DOT 1 (-775 4425);
DOT 1 (-775 4475);
DOT 1 (-775 4375);
DOT 1 (-775 4525);
DOT 1 (-2625 4525);
DOT 1 (-2625 4375);
DOT 1 (-2625 4475);
DOT 1 (-2625 4425);
DOT 1 (-2625 4275);
DOT 1 (-2625 4325);
DOT 1 (-2625 4225);
DOT 1 (-2625 4125);
DOT 1 (-2625 4175);
DOT 1 (-2625 4025);
DOT 1 (-2625 4075);
DOT 1 (-2625 3975);
DOT 1 (-2625 3875);
DOT 1 (-2625 3925);
DOT 1 (-2625 3775);
DOT 1 (-2625 3825);
DOT 1 (-2625 3725);
DOT 1 (-2625 3625);
DOT 1 (-2625 3675);
DOT 1 (-2625 3475);
DOT 1 (-2625 3575);
DOT 1 (-2625 3525);
DOT 1 (-2625 3375);
DOT 1 (-2625 3425);
DOT 1 (-2625 3225);
DOT 1 (-2625 3325);
DOT 1 (-2625 3275);
DOT 1 (-2625 3125);
DOT 1 (-2625 3175);
DOT 1 (-2625 3075);
DOT 1 (-2625 2975);
DOT 1 (-2625 3025);
DOT 1 (-2625 2875);
DOT 1 (-2625 2925);
DOT 1 (-2625 2825);
DOT 1 (-2625 2775);
DOT 1 (-2625 2725);
DOT 1 (-2625 2575);
DOT 1 (-2625 2625);
DOT 1 (-2625 2675);
DOT 1 (-2625 2525);
DOT 1 (-2625 2475);
DOT 1 (-2625 2325);
DOT 1 (-2625 2375);
DOT 1 (-2625 2425);
DOT 1 (-2625 2275);
DOT 1 (-2625 2225);
DOT 1 (-2625 2075);
DOT 1 (-2625 2125);
DOT 1 (-2625 2175);
DOT 1 (-2625 1975);
DOT 1 (-2625 2025);
DOT 1 (-2625 1825);
DOT 1 (-2625 1875);
DOT 1 (-2625 1725);
DOT 1 (-2625 1775);
DOT 1 (-2625 1575);
DOT 1 (-2625 1475);
DOT 1 (-2625 1375);
DOT 1 (-2625 1325);
DOT 1 (-2625 1175);
DOT 1 (-2625 1275);
DOT 1 (-2625 1225);
DOT 1 (-2625 1075);
DOT 1 (-2625 1125);
DOT 1 (-2625 1025);
DOT 1 (-2625 925);
DOT 1 (-2625 675);
DOT 1 (-2625 625);
DOT 1 (-2325 1325);
DOT 1 (-2325 1675);
DOT 1 (-4450 1375);
DOT 1 (-2325 4525);
DOT 1 (-2325 4475);
DOT 1 (-2325 4375);
DOT 1 (-2325 4425);
DOT 1 (-2325 4325);
DOT 1 (-2325 4275);
DOT 1 (-2325 4225);
DOT 1 (-2325 4175);
DOT 1 (-2325 4125);
DOT 1 (-2325 4075);
DOT 1 (-2325 4025);
DOT 1 (-2325 3975);
DOT 1 (-2325 3925);
DOT 1 (-2325 3875);
DOT 1 (-2325 3825);
DOT 1 (-2325 3725);
DOT 1 (-2325 3775);
DOT 1 (-2325 3675);
DOT 1 (-2325 3625);
DOT 1 (-2325 3575);
DOT 1 (-2325 3475);
DOT 1 (-2325 3525);
DOT 1 (-2325 3425);
DOT 1 (-2325 3375);
DOT 1 (-2325 3325);
DOT 1 (-2325 3225);
DOT 1 (-2325 3075);
DOT 1 (-2325 3125);
DOT 1 (-2325 3175);
DOT 1 (-2325 3025);
DOT 1 (-2325 2975);
DOT 1 (-2325 2925);
DOT 1 (-2325 2825);
DOT 1 (-2325 2875);
DOT 1 (-2325 2775);
DOT 1 (-2325 2725);
DOT 1 (-2325 2675);
DOT 1 (-2325 2575);
DOT 1 (-2325 2625);
DOT 1 (-2325 2525);
DOT 1 (-2325 2475);
DOT 1 (-2325 2425);
DOT 1 (-2325 2325);
DOT 1 (-2325 2275);
DOT 1 (-2325 2225);
DOT 1 (-2325 2175);
DOT 1 (-2325 2125);
DOT 1 (-2325 2075);
DOT 1 (-2325 2025);
DOT 1 (-2325 1925);
DOT 1 (-2325 1975);
DOT 1 (-2325 1875);
DOT 1 (-2325 1825);
DOT 1 (-2325 1775);
DOT 1 (-2325 1725);
DOT 1 (-2325 1625);
DOT 1 (-2325 1525);
DOT 1 (-2325 1575);
DOT 1 (-2325 1425);
DOT 1 (-2325 1475);
DOT 1 (-2325 1375);
DOT 1 (-2325 1275);
DOT 1 (-2325 1175);
DOT 1 (-2325 1225);
DOT 1 (-2325 1125);
DOT 1 (-2325 1075);
DOT 1 (-2325 1025);
DOT 1 (-2325 975);
DOT 1 (-4150 4475);
DOT 1 (-4150 4525);
DOT 1 (-4150 4425);
DOT 1 (-4150 4375);
DOT 1 (-4150 4225);
DOT 1 (-4150 4275);
DOT 1 (-4150 4325);
DOT 1 (-4150 4125);
DOT 1 (-4150 4175);
DOT 1 (-4150 4075);
DOT 1 (-4150 3975);
DOT 1 (-4150 4025);
DOT 1 (-4150 3875);
DOT 1 (-4150 3825);
DOT 1 (-4150 3775);
DOT 1 (-4150 3725);
DOT 1 (-4150 3575);
DOT 1 (-4150 3675);
DOT 1 (-4150 3525);
DOT 1 (-4150 3475);
DOT 1 (-4150 3325);
DOT 1 (-4150 3375);
DOT 1 (-4150 3425);
DOT 1 (-4150 3275);
DOT 1 (-4150 3225);
DOT 1 (-4150 3125);
DOT 1 (-4150 3175);
DOT 1 (-4150 3075);
DOT 1 (-4150 2975);
DOT 1 (-4150 3025);
DOT 1 (-4150 2925);
DOT 1 (-4150 2875);
DOT 1 (-4150 2825);
DOT 1 (-4150 2775);
DOT 1 (-4150 2475);
DOT 1 (-4150 2525);
DOT 1 (-4150 2325);
DOT 1 (-4150 2175);
DOT 1 (-4150 2225);
DOT 1 (-4150 2275);
DOT 1 (-4150 2075);
DOT 1 (-4150 2125);
DOT 1 (-4150 2025);
DOT 1 (-4150 1975);
DOT 1 (-4150 1925);
DOT 1 (-4150 1825);
DOT 1 (-4150 1875);
DOT 1 (-4150 1775);
DOT 1 (-4150 1725);
DOT 1 (-4150 1675);
DOT 1 (-4150 1525);
DOT 1 (-4150 1625);
DOT 1 (-4150 1575);
DOT 1 (-4150 1425);
DOT 1 (-4150 1475);
DOT 1 (-4150 1275);
DOT 1 (-4150 1225);
DOT 1 (-4150 1175);
DOT 1 (-4150 1025);
DOT 1 (-4150 1075);
DOT 1 (-4150 1125);
DOT 1 (-4150 925);
DOT 1 (-4150 975);
DOT 1 (-4150 875);
DOT 1 (-4150 825);
DOT 1 (-4150 775);
DOT 1 (-4150 675);
DOT 1 (-4150 725);
DOT 1 (-4150 625);
DOT 1 (-5975 725);
DOT 1 (-5975 775);
DOT 1 (-5975 825);
DOT 1 (-5975 925);
DOT 1 (-5975 875);
DOT 1 (-5975 975);
DOT 1 (-5975 1025);
DOT 1 (-5975 1075);
DOT 1 (-5975 1225);
DOT 1 (-5975 1125);
DOT 1 (-5975 1175);
DOT 1 (-5975 1325);
DOT 1 (-5975 1275);
DOT 1 (-5975 1475);
DOT 1 (-5975 1375);
DOT 1 (-5975 1575);
DOT 1 (-5975 1525);
DOT 1 (-5975 1625);
DOT 1 (-5975 1825);
DOT 1 (-5975 1875);
DOT 1 (-5975 1975);
DOT 1 (-5975 2125);
DOT 1 (-5975 2175);
DOT 1 (-5975 2225);
DOT 1 (-5975 2325);
DOT 1 (-5975 2375);
DOT 1 (-5975 2425);
DOT 1 (-5975 2575);
DOT 1 (-5975 2525);
DOT 1 (-5975 2625);
DOT 1 (-5975 2725);
DOT 1 (-5975 2775);
DOT 1 (-5975 2825);
DOT 1 (-5975 2875);
DOT 1 (-5975 2925);
DOT 1 (-5975 2975);
DOT 1 (-5975 3025);
DOT 1 (-5975 3075);
DOT 1 (-5975 3125);
DOT 1 (-5975 3175);
DOT 1 (-5975 3225);
DOT 1 (-5975 3375);
DOT 1 (-5975 3325);
DOT 1 (-5975 3425);
DOT 1 (-5975 3475);
DOT 1 (-5975 3625);
DOT 1 (-5975 3775);
DOT 1 (-5975 3825);
DOT 1 (-5975 3925);
DOT 1 (-5975 4025);
DOT 1 (-5975 3975);
DOT 1 (-4450 675);
DOT 1 (-4450 625);
DOT 1 (-4450 725);
DOT 1 (-4450 775);
DOT 1 (-4450 825);
DOT 1 (-4450 875);
DOT 1 (-4450 925);
DOT 1 (-4450 975);
DOT 1 (-4450 1025);
DOT 1 (-4450 1075);
DOT 1 (-4450 1125);
DOT 1 (-4450 1175);
DOT 1 (-4450 1225);
DOT 1 (-4450 1325);
DOT 1 (-4450 1275);
DOT 1 (-4450 1425);
DOT 1 (-4450 1475);
DOT 1 (-4450 1525);
DOT 1 (-4450 1575);
DOT 1 (-4450 1625);
DOT 1 (-4450 1825);
DOT 1 (-4450 1775);
DOT 1 (-4450 1875);
DOT 1 (-4450 1925);
DOT 1 (-4450 1975);
DOT 1 (-4450 2025);
DOT 1 (-4450 2075);
DOT 1 (-4450 2125);
DOT 1 (-4450 2225);
DOT 1 (-4450 2175);
DOT 1 (-4450 2275);
DOT 1 (-4450 2325);
DOT 1 (-4450 2375);
DOT 1 (-4450 2475);
DOT 1 (-4450 2525);
DOT 1 (-4450 2575);
DOT 1 (-4450 2625);
DOT 1 (-4450 2725);
DOT 1 (-4450 2675);
DOT 1 (-4450 2775);
DOT 1 (-4450 2825);
DOT 1 (-4450 2875);
DOT 1 (-4450 2925);
DOT 1 (-4450 2975);
DOT 1 (-4450 3025);
DOT 1 (-4450 3075);
DOT 1 (-4450 3125);
DOT 1 (-4450 3175);
DOT 1 (-4450 3225);
DOT 1 (-4450 3275);
DOT 1 (-4450 3375);
DOT 1 (-4450 3325);
DOT 1 (-4450 3425);
DOT 1 (-4450 3475);
DOT 1 (-4450 3525);
DOT 1 (-4450 3625);
DOT 1 (-4450 3575);
DOT 1 (-4450 3875);
DOT 1 (-4450 3825);
DOT 1 (-4450 3925);
DOT 1 (-4450 3975);
DOT 1 (-4450 4025);
DOT 1 (-5975 4125);
DOT 1 (-5975 4075);
DOT 1 (-5975 4175);
DOT 1 (-5975 4225);
DOT 1 (-4450 4125);
DOT 1 (-4450 4175);
DOT 1 (-4450 4275);
DOT 1 (-4450 4325);
DOT 1 (-4450 4375);
DOT 1 (-4450 4425);
DOT 1 (-4450 4525);
DOT 1 (-4450 4475);
DOT 1 (-7800 625);
DOT 1 (-7800 725);
DOT 1 (-7800 675);
DOT 1 (-7800 775);
DOT 1 (-7800 825);
DOT 1 (-7800 875);
DOT 1 (-7800 975);
DOT 1 (-7800 925);
DOT 1 (-7800 1125);
DOT 1 (-7800 1075);
DOT 1 (-7800 1025);
DOT 1 (-7800 1225);
DOT 1 (-7800 1175);
DOT 1 (-7800 1375);
DOT 1 (-7800 1325);
DOT 1 (-7800 1275);
DOT 1 (-7800 1475);
DOT 1 (-7800 1425);
DOT 1 (-7800 1575);
DOT 1 (-7800 1625);
DOT 1 (-7800 1525);
DOT 1 (-7800 1675);
DOT 1 (-7800 1725);
DOT 1 (-7800 1775);
DOT 1 (-7800 1875);
DOT 1 (-7800 1825);
DOT 1 (-7800 1975);
DOT 1 (-7800 1925);
DOT 1 (-7800 2025);
DOT 1 (-7800 2125);
DOT 1 (-7800 2075);
DOT 1 (-7800 2275);
DOT 1 (-7800 2225);
DOT 1 (-7800 2175);
DOT 1 (-7800 2375);
DOT 1 (-7800 2325);
DOT 1 (-7800 2425);
DOT 1 (-7800 2475);
DOT 1 (-7800 2625);
DOT 1 (-7800 2575);
DOT 1 (-7800 2675);
DOT 1 (-7800 2775);
DOT 1 (-7800 2725);
DOT 1 (-7800 2875);
DOT 1 (-7800 2825);
DOT 1 (-7800 2925);
DOT 1 (-7800 3025);
DOT 1 (-7800 2975);
DOT 1 (-7800 3175);
DOT 1 (-7800 3075);
DOT 1 (-7800 3125);
DOT 1 (-7800 3275);
DOT 1 (-7800 3225);
DOT 1 (-7800 3425);
DOT 1 (-7800 3375);
DOT 1 (-7800 3325);
DOT 1 (-7800 3525);
DOT 1 (-7800 3475);
DOT 1 (-7800 3675);
DOT 1 (-7800 3625);
DOT 1 (-7800 3575);
DOT 1 (-7800 3775);
DOT 1 (-7800 3725);
DOT 1 (-7800 3825);
DOT 1 (-7800 3875);
DOT 1 (-7800 4025);
DOT 1 (-7800 3975);
DOT 1 (-6275 625);
DOT 1 (-6275 725);
DOT 1 (-6275 675);
DOT 1 (-6275 775);
DOT 1 (-6275 825);
DOT 1 (-6275 975);
DOT 1 (-6275 925);
DOT 1 (-6275 1025);
DOT 1 (-6275 1075);
DOT 1 (-6275 1125);
DOT 1 (-6275 1225);
DOT 1 (-6275 1175);
DOT 1 (-6275 1325);
DOT 1 (-6275 1375);
DOT 1 (-6275 1475);
DOT 1 (-6275 1425);
DOT 1 (-6275 1525);
DOT 1 (-6275 1575);
DOT 1 (-6275 1725);
DOT 1 (-6275 1675);
DOT 1 (-6275 1775);
DOT 1 (-6275 1825);
DOT 1 (-6275 1875);
DOT 1 (-6275 1925);
DOT 1 (-6275 1975);
DOT 1 (-6275 2025);
DOT 1 (-6275 2075);
DOT 1 (-6275 2275);
DOT 1 (-6275 2175);
DOT 1 (-6275 2325);
DOT 1 (-6275 2375);
DOT 1 (-6275 2525);
DOT 1 (-6275 2475);
DOT 1 (-6275 2425);
DOT 1 (-6275 2575);
DOT 1 (-6275 2675);
DOT 1 (-6275 2775);
DOT 1 (-6275 2725);
DOT 1 (-6275 2875);
DOT 1 (-6275 2925);
DOT 1 (-6275 3025);
DOT 1 (-6275 2975);
DOT 1 (-6275 3075);
DOT 1 (-6275 3225);
DOT 1 (-6275 3425);
DOT 1 (-6275 3375);
DOT 1 (-6275 3325);
DOT 1 (-6275 3525);
DOT 1 (-6275 3475);
DOT 1 (-6275 3575);
DOT 1 (-6275 3775);
DOT 1 (-6275 3725);
DOT 1 (-6275 3825);
DOT 1 (-6275 3925);
DOT 1 (-7800 4075);
DOT 1 (-7800 4175);
DOT 1 (-7800 4125);
DOT 1 (-7800 4325);
DOT 1 (-7800 4275);
DOT 1 (-7800 4225);
DOT 1 (-7800 4425);
DOT 1 (-7800 4375);
DOT 1 (-7800 4525);
DOT 1 (-7800 4475);
DOT 1 (-6275 4275);
DOT 1 (-6275 4225);
DOT 1 (-6275 4375);
DOT 1 (-4450 2425);
DOT 1 (-6275 4475);
DOT 1 (-5975 625);
DOT 1 (-6275 3125);
DOT 1 (-7800 3925);
DOT 1 (-5975 3675);
DOT 1 (-5975 1425);
DOT 1 (-7800 2525);
DOT 1 (-6275 2225);
DOT 1 (-5975 4525);
DOT 1 (-6275 3875);
DOT 1 (-6275 3675);
DOT 1 (-6275 4125);
DOT 1 (-6275 4025);
DOT 1 (-2325 3275);
DOT 1 (-775 3625);
DOT 1 (-4450 3775);
DOT 1 (-4450 4075);
DOT 1 (-6275 4425);
FORCENOTE
BOM_COST=PROC_SOCKET
(-8225 200) 0;
DISPLAY LEFT (-8225 200);
DISPLAY 1.382979 (-8225 200);
PAINT PURPLE (-8225 200);
FORCENOTE
ROOM=CPU0
(-8150 325) 0;
DISPLAY LEFT (-8150 325);
DISPLAY 1.382979 (-8150 325);
PAINT PURPLE (-8150 325);
QUIT
